G04*
G04 #@! TF.GenerationSoftware,Altium Limited,Altium Designer,23.6.0 (18)*
G04*
G04 Layer_Color=32896*
%FSLAX44Y44*%
%MOMM*%
G71*
G04*
G04 #@! TF.SameCoordinates,B62FFF2A-40BB-47C2-B022-6C0D6E2DF31E*
G04*
G04*
G04 #@! TF.FilePolarity,Positive*
G04*
G01*
G75*
%ADD16C,0.1000*%
G36*
X25444Y350267D02*
X25582D01*
Y349718D01*
X25719D01*
Y349444D01*
X25856D01*
Y349169D01*
X25994D01*
Y348894D01*
X26131D01*
Y348757D01*
X26268D01*
Y348482D01*
X26406D01*
Y348345D01*
X26543D01*
Y348208D01*
X26680D01*
Y348070D01*
X26955D01*
Y347933D01*
X27092D01*
Y347796D01*
X27367D01*
Y347659D01*
X27641D01*
Y347521D01*
X27916D01*
Y347384D01*
X28603D01*
Y347247D01*
X177180D01*
Y342166D01*
X27229D01*
Y342303D01*
X26543D01*
Y342440D01*
X25994D01*
Y342578D01*
X25719D01*
Y342715D01*
X25307D01*
Y342852D01*
X25032D01*
Y342990D01*
X24758D01*
Y343127D01*
X24483D01*
Y343264D01*
X24209D01*
Y343402D01*
X24071D01*
Y343539D01*
X23797D01*
Y343676D01*
X23659D01*
Y343814D01*
X23522D01*
Y343951D01*
X23247D01*
Y344088D01*
X23110D01*
Y344226D01*
X22973D01*
Y344363D01*
X22835D01*
Y344500D01*
X22698D01*
Y344637D01*
X22561D01*
Y344775D01*
X22423D01*
Y344912D01*
X22286D01*
Y345049D01*
X22149D01*
Y345324D01*
X22011D01*
Y345461D01*
X21874D01*
Y345599D01*
X21737D01*
Y345873D01*
X21600D01*
Y346011D01*
X21462D01*
Y346285D01*
X21325D01*
Y346560D01*
X21188D01*
Y346835D01*
X21050D01*
Y347109D01*
X20913D01*
Y347521D01*
X20776D01*
Y347796D01*
X20638D01*
Y348345D01*
X20501D01*
Y348894D01*
X20364D01*
Y350267D01*
X20226D01*
Y367707D01*
X25444D01*
Y350267D01*
D02*
G37*
G36*
X139143Y336398D02*
X139830D01*
Y336261D01*
X140242D01*
Y336124D01*
X140517D01*
Y335987D01*
X140791D01*
Y335849D01*
X141066D01*
Y335712D01*
X141340D01*
Y335574D01*
X141478D01*
Y335437D01*
X141752D01*
Y335300D01*
X141890D01*
Y335163D01*
X142027D01*
Y335025D01*
X142164D01*
Y334888D01*
X142302D01*
Y334751D01*
X142439D01*
Y334476D01*
X142576D01*
Y334339D01*
X142714D01*
Y334201D01*
X142851D01*
Y333927D01*
X142988D01*
Y333652D01*
X143125D01*
Y333377D01*
X143263D01*
Y332966D01*
X143400D01*
Y332553D01*
X143538D01*
Y330219D01*
X143400D01*
Y329807D01*
X143263D01*
Y329395D01*
X143125D01*
Y329121D01*
X142988D01*
Y328846D01*
X142851D01*
Y328571D01*
X142714D01*
Y328434D01*
X142576D01*
Y328159D01*
X142439D01*
Y328022D01*
X142302D01*
Y327885D01*
X142164D01*
Y327747D01*
X142027D01*
Y327610D01*
X141890D01*
Y327473D01*
X141752D01*
Y327336D01*
X141615D01*
Y327198D01*
X141340D01*
Y327061D01*
X141203D01*
Y326923D01*
X140928D01*
Y326786D01*
X140654D01*
Y326649D01*
X140379D01*
Y326512D01*
X139967D01*
Y326374D01*
X139281D01*
Y326237D01*
X137633D01*
Y326374D01*
X136946D01*
Y326512D01*
X136534D01*
Y326649D01*
X136260D01*
Y326786D01*
X135985D01*
Y326923D01*
X135710D01*
Y327061D01*
X135573D01*
Y327198D01*
X135298D01*
Y327336D01*
X135161D01*
Y327473D01*
X135024D01*
Y327610D01*
X134887D01*
Y327747D01*
X134749D01*
Y327885D01*
X134612D01*
Y328022D01*
X134474D01*
Y328159D01*
X134337D01*
Y328434D01*
X134200D01*
Y328571D01*
X134063D01*
Y328846D01*
X133925D01*
Y329121D01*
X133788D01*
Y329395D01*
X133651D01*
Y329670D01*
X133513D01*
Y330219D01*
X133376D01*
Y332553D01*
X133513D01*
Y332966D01*
X133651D01*
Y333377D01*
X133788D01*
Y333652D01*
X133925D01*
Y333927D01*
X134063D01*
Y334201D01*
X134200D01*
Y334339D01*
X134337D01*
Y334613D01*
X134474D01*
Y334751D01*
X134612D01*
Y334888D01*
X134749D01*
Y335025D01*
X134887D01*
Y335163D01*
X135024D01*
Y335300D01*
X135161D01*
Y335437D01*
X135436D01*
Y335574D01*
X135573D01*
Y335712D01*
X135848D01*
Y335849D01*
X136122D01*
Y335987D01*
X136397D01*
Y336124D01*
X136672D01*
Y336261D01*
X137084D01*
Y336398D01*
X137770D01*
Y336536D01*
X139143D01*
Y336398D01*
D02*
G37*
G36*
X120605D02*
X121292D01*
Y336261D01*
X121704D01*
Y336124D01*
X121979D01*
Y335987D01*
X122253D01*
Y335849D01*
X122528D01*
Y335712D01*
X122802D01*
Y335574D01*
X122940D01*
Y335437D01*
X123077D01*
Y335300D01*
X123352D01*
Y335163D01*
X123489D01*
Y335025D01*
X123626D01*
Y334888D01*
X123764D01*
Y334613D01*
X123901D01*
Y334476D01*
X124038D01*
Y334339D01*
X124176D01*
Y334064D01*
X124313D01*
Y333789D01*
X124450D01*
Y333652D01*
X124588D01*
Y333240D01*
X124725D01*
Y332828D01*
X124862D01*
Y332416D01*
X125000D01*
Y330356D01*
X124862D01*
Y329807D01*
X124725D01*
Y329533D01*
X124588D01*
Y329121D01*
X124450D01*
Y328846D01*
X124313D01*
Y328709D01*
X124176D01*
Y328434D01*
X124038D01*
Y328297D01*
X123901D01*
Y328022D01*
X123764D01*
Y327885D01*
X123626D01*
Y327747D01*
X123489D01*
Y327610D01*
X123352D01*
Y327473D01*
X123215D01*
Y327336D01*
X122940D01*
Y327198D01*
X122802D01*
Y327061D01*
X122528D01*
Y326923D01*
X122391D01*
Y326786D01*
X122116D01*
Y326649D01*
X121704D01*
Y326512D01*
X121292D01*
Y326374D01*
X120743D01*
Y326237D01*
X118958D01*
Y326374D01*
X118408D01*
Y326512D01*
X117996D01*
Y326649D01*
X117722D01*
Y326786D01*
X117447D01*
Y326923D01*
X117172D01*
Y327061D01*
X117035D01*
Y327198D01*
X116761D01*
Y327336D01*
X116623D01*
Y327473D01*
X116486D01*
Y327610D01*
X116349D01*
Y327747D01*
X116211D01*
Y327885D01*
X116074D01*
Y328022D01*
X115937D01*
Y328159D01*
X115799D01*
Y328297D01*
X115662D01*
Y328571D01*
X115525D01*
Y328709D01*
X115387D01*
Y328983D01*
X115250D01*
Y329258D01*
X115113D01*
Y329670D01*
X114975D01*
Y330082D01*
X114838D01*
Y330768D01*
X114701D01*
Y332004D01*
X114838D01*
Y332691D01*
X114975D01*
Y333103D01*
X115113D01*
Y333515D01*
X115250D01*
Y333789D01*
X115387D01*
Y333927D01*
X115525D01*
Y334201D01*
X115662D01*
Y334476D01*
X115799D01*
Y334613D01*
X115937D01*
Y334751D01*
X116074D01*
Y334888D01*
X116211D01*
Y335025D01*
X116349D01*
Y335163D01*
X116486D01*
Y335300D01*
X116623D01*
Y335437D01*
X116761D01*
Y335574D01*
X117035D01*
Y335712D01*
X117172D01*
Y335849D01*
X117447D01*
Y335987D01*
X117722D01*
Y336124D01*
X118134D01*
Y336261D01*
X118546D01*
Y336398D01*
X119232D01*
Y336536D01*
X120605D01*
Y336398D01*
D02*
G37*
G36*
X102068D02*
X102617D01*
Y336261D01*
X103029D01*
Y336124D01*
X103441D01*
Y335987D01*
X103715D01*
Y335849D01*
X103990D01*
Y335712D01*
X104127D01*
Y335574D01*
X104402D01*
Y335437D01*
X104539D01*
Y335300D01*
X104677D01*
Y335163D01*
X104814D01*
Y335025D01*
X104951D01*
Y334888D01*
X105089D01*
Y334751D01*
X105226D01*
Y334613D01*
X105363D01*
Y334476D01*
X105500D01*
Y334201D01*
X105638D01*
Y334064D01*
X105775D01*
Y333789D01*
X105913D01*
Y333515D01*
X106050D01*
Y333240D01*
X106187D01*
Y332828D01*
X106324D01*
Y332142D01*
X106462D01*
Y330631D01*
X106324D01*
Y329944D01*
X106187D01*
Y329533D01*
X106050D01*
Y329258D01*
X105913D01*
Y328983D01*
X105775D01*
Y328709D01*
X105638D01*
Y328434D01*
X105500D01*
Y328297D01*
X105363D01*
Y328159D01*
X105226D01*
Y328022D01*
X105089D01*
Y327747D01*
X104951D01*
Y327610D01*
X104814D01*
Y327473D01*
X104539D01*
Y327336D01*
X104402D01*
Y327198D01*
X104265D01*
Y327061D01*
X103990D01*
Y326923D01*
X103715D01*
Y326786D01*
X103441D01*
Y326649D01*
X103166D01*
Y326512D01*
X102754D01*
Y326374D01*
X102205D01*
Y326237D01*
X100420D01*
Y326374D01*
X99871D01*
Y326512D01*
X99459D01*
Y326649D01*
X99184D01*
Y326786D01*
X98909D01*
Y326923D01*
X98635D01*
Y327061D01*
X98360D01*
Y327198D01*
X98223D01*
Y327336D01*
X98085D01*
Y327473D01*
X97811D01*
Y327610D01*
X97673D01*
Y327747D01*
X97536D01*
Y327885D01*
X97399D01*
Y328159D01*
X97261D01*
Y328297D01*
X97124D01*
Y328434D01*
X96987D01*
Y328709D01*
X96849D01*
Y328983D01*
X96712D01*
Y329258D01*
X96575D01*
Y329533D01*
X96438D01*
Y329944D01*
X96300D01*
Y330494D01*
X96163D01*
Y332142D01*
X96300D01*
Y332828D01*
X96438D01*
Y333240D01*
X96575D01*
Y333515D01*
X96712D01*
Y333789D01*
X96849D01*
Y334064D01*
X96987D01*
Y334201D01*
X97124D01*
Y334476D01*
X97261D01*
Y334613D01*
X97399D01*
Y334751D01*
X97536D01*
Y334888D01*
X97673D01*
Y335025D01*
X97811D01*
Y335163D01*
X97948D01*
Y335300D01*
X98085D01*
Y335437D01*
X98223D01*
Y335574D01*
X98497D01*
Y335712D01*
X98635D01*
Y335849D01*
X98909D01*
Y335987D01*
X99184D01*
Y336124D01*
X99459D01*
Y336261D01*
X100008D01*
Y336398D01*
X100557D01*
Y336536D01*
X102068D01*
Y336398D01*
D02*
G37*
G36*
X83392D02*
X84079D01*
Y336261D01*
X84491D01*
Y336124D01*
X84903D01*
Y335987D01*
X85177D01*
Y335849D01*
X85315D01*
Y335712D01*
X85590D01*
Y335574D01*
X85864D01*
Y335437D01*
X86001D01*
Y335300D01*
X86139D01*
Y335163D01*
X86276D01*
Y335025D01*
X86413D01*
Y334888D01*
X86551D01*
Y334751D01*
X86688D01*
Y334613D01*
X86825D01*
Y334339D01*
X86963D01*
Y334201D01*
X87100D01*
Y333927D01*
X87237D01*
Y333789D01*
X87375D01*
Y333377D01*
X87512D01*
Y333103D01*
X87649D01*
Y332691D01*
X87787D01*
Y331867D01*
X87924D01*
Y330906D01*
X87787D01*
Y330082D01*
X87649D01*
Y329670D01*
X87512D01*
Y329258D01*
X87375D01*
Y328983D01*
X87237D01*
Y328709D01*
X87100D01*
Y328571D01*
X86963D01*
Y328297D01*
X86825D01*
Y328159D01*
X86688D01*
Y328022D01*
X86551D01*
Y327885D01*
X86413D01*
Y327747D01*
X86276D01*
Y327610D01*
X86139D01*
Y327473D01*
X86001D01*
Y327336D01*
X85864D01*
Y327198D01*
X85590D01*
Y327061D01*
X85452D01*
Y326923D01*
X85177D01*
Y326786D01*
X84903D01*
Y326649D01*
X84628D01*
Y326512D01*
X84216D01*
Y326374D01*
X83667D01*
Y326237D01*
X81882D01*
Y326374D01*
X81333D01*
Y326512D01*
X80921D01*
Y326649D01*
X80509D01*
Y326786D01*
X80234D01*
Y326923D01*
X80097D01*
Y327061D01*
X79822D01*
Y327198D01*
X79685D01*
Y327336D01*
X79410D01*
Y327473D01*
X79273D01*
Y327610D01*
X79136D01*
Y327747D01*
X78998D01*
Y327885D01*
X78861D01*
Y328022D01*
X78724D01*
Y328297D01*
X78586D01*
Y328434D01*
X78449D01*
Y328709D01*
X78312D01*
Y328846D01*
X78174D01*
Y329121D01*
X78037D01*
Y329395D01*
X77900D01*
Y329807D01*
X77762D01*
Y330356D01*
X77625D01*
Y332416D01*
X77762D01*
Y332966D01*
X77900D01*
Y333240D01*
X78037D01*
Y333652D01*
X78174D01*
Y333927D01*
X78312D01*
Y334064D01*
X78449D01*
Y334339D01*
X78586D01*
Y334476D01*
X78724D01*
Y334613D01*
X78861D01*
Y334888D01*
X78998D01*
Y335025D01*
X79136D01*
Y335163D01*
X79273D01*
Y335300D01*
X79548D01*
Y335437D01*
X79685D01*
Y335574D01*
X79822D01*
Y335712D01*
X80097D01*
Y335849D01*
X80371D01*
Y335987D01*
X80646D01*
Y336124D01*
X80921D01*
Y336261D01*
X81333D01*
Y336398D01*
X82019D01*
Y336536D01*
X83392D01*
Y336398D01*
D02*
G37*
G36*
X158368Y316625D02*
X146421D01*
Y316487D01*
X146146D01*
Y316350D01*
X146009D01*
Y316213D01*
X145872D01*
Y316075D01*
X145735D01*
Y315801D01*
X145597D01*
Y294517D01*
X145735D01*
Y294242D01*
X145872D01*
Y293967D01*
X146009D01*
Y293830D01*
X146284D01*
Y293693D01*
X147108D01*
Y293555D01*
X147245D01*
Y293693D01*
X147382D01*
Y293555D01*
X147657D01*
Y293693D01*
X154660D01*
Y293555D01*
X155072D01*
Y293418D01*
X155210D01*
Y293281D01*
X155347D01*
Y293143D01*
X155484D01*
Y293006D01*
X155621D01*
Y292594D01*
X155759D01*
Y284355D01*
X155621D01*
Y283943D01*
X155484D01*
Y283806D01*
X155347D01*
Y283668D01*
X155210D01*
Y283531D01*
X155072D01*
Y283394D01*
X154523D01*
Y283257D01*
X148618D01*
Y283394D01*
X148481D01*
Y283257D01*
X148206D01*
Y283394D01*
X148069D01*
Y283257D01*
X147245D01*
Y283119D01*
X146970D01*
Y282982D01*
X146696D01*
Y282845D01*
X146559D01*
Y282707D01*
X146421D01*
Y282570D01*
X146284D01*
Y282433D01*
X146146D01*
Y282295D01*
X146009D01*
Y282021D01*
X145872D01*
Y281746D01*
X145735D01*
Y281334D01*
X145597D01*
Y280236D01*
X145735D01*
Y279824D01*
X145872D01*
Y279549D01*
X146009D01*
Y279274D01*
X146146D01*
Y279137D01*
X146284D01*
Y279000D01*
X146421D01*
Y278862D01*
X146559D01*
Y278725D01*
X146833D01*
Y278588D01*
X147108D01*
Y278450D01*
X147382D01*
Y278313D01*
X148618D01*
Y278176D01*
X148756D01*
Y278313D01*
X159878D01*
Y278176D01*
X160290D01*
Y278039D01*
X160565D01*
Y277901D01*
X160702D01*
Y277626D01*
X160840D01*
Y277352D01*
X160977D01*
Y263895D01*
X160840D01*
Y263483D01*
X160702D01*
Y263346D01*
X160565D01*
Y263208D01*
X160427D01*
Y263071D01*
X160290D01*
Y262934D01*
X151914D01*
Y262796D01*
X151365D01*
Y262659D01*
X151227D01*
Y262522D01*
X151090D01*
Y262384D01*
X150953D01*
Y262247D01*
X150815D01*
Y261835D01*
X150678D01*
Y261423D01*
X150815D01*
Y261011D01*
X150953D01*
Y260737D01*
X151090D01*
Y260599D01*
X151365D01*
Y260462D01*
X151777D01*
Y260324D01*
X160153D01*
Y260187D01*
X160427D01*
Y260050D01*
X160565D01*
Y259913D01*
X160702D01*
Y259775D01*
X160840D01*
Y259363D01*
X160977D01*
Y233136D01*
X160840D01*
Y232861D01*
X160702D01*
Y232586D01*
X160565D01*
Y232449D01*
X160290D01*
Y232312D01*
X160016D01*
Y232174D01*
X146421D01*
Y232037D01*
X146146D01*
Y231900D01*
X146009D01*
Y231763D01*
X145872D01*
Y231625D01*
X145735D01*
Y231350D01*
X145597D01*
Y132482D01*
X145460D01*
Y131933D01*
X145323D01*
Y131521D01*
X145185D01*
Y131246D01*
X145048D01*
Y130971D01*
X144911D01*
Y130697D01*
X144773D01*
Y130422D01*
X144636D01*
Y130285D01*
X144499D01*
Y130010D01*
X144361D01*
Y129873D01*
X144224D01*
Y129736D01*
X144087D01*
Y129461D01*
X143949D01*
Y129324D01*
X143812D01*
Y129186D01*
X143675D01*
Y129049D01*
X143538D01*
Y128912D01*
X143400D01*
Y128774D01*
X143263D01*
Y128637D01*
X143125D01*
Y128500D01*
X142988D01*
Y128362D01*
X142851D01*
Y128225D01*
X142714D01*
Y128088D01*
X142439D01*
Y127950D01*
X142302D01*
Y127813D01*
X142164D01*
Y127676D01*
X141890D01*
Y127538D01*
X141752D01*
Y127401D01*
X141478D01*
Y127264D01*
X141340D01*
Y127127D01*
X141066D01*
Y126989D01*
X140791D01*
Y126852D01*
X140517D01*
Y126715D01*
X140105D01*
Y126577D01*
X139693D01*
Y126440D01*
X139281D01*
Y126303D01*
X138869D01*
Y126165D01*
X138182D01*
Y126028D01*
X136809D01*
Y125891D01*
X136534D01*
Y126028D01*
X135298D01*
Y126165D01*
X134474D01*
Y126303D01*
X134063D01*
Y126440D01*
X133651D01*
Y126577D01*
X133239D01*
Y126715D01*
X132964D01*
Y126852D01*
X132689D01*
Y126989D01*
X132415D01*
Y127127D01*
X132140D01*
Y127264D01*
X132003D01*
Y127401D01*
X131728D01*
Y127538D01*
X131591D01*
Y127676D01*
X131316D01*
Y127813D01*
X131179D01*
Y127950D01*
X131042D01*
Y128088D01*
X130904D01*
Y128225D01*
X130630D01*
Y128362D01*
X130492D01*
Y128500D01*
X130355D01*
Y128637D01*
X130218D01*
Y128774D01*
X130080D01*
Y128912D01*
X129943D01*
Y129186D01*
X129806D01*
Y129324D01*
X129668D01*
Y129461D01*
X129531D01*
Y129598D01*
X129394D01*
Y129873D01*
X129256D01*
Y130010D01*
X129119D01*
Y130285D01*
X128982D01*
Y130560D01*
X128844D01*
Y130697D01*
X128707D01*
Y130971D01*
X128570D01*
Y131246D01*
X128433D01*
Y131658D01*
X128295D01*
Y132070D01*
X128158D01*
Y132482D01*
X128021D01*
Y132894D01*
X127883D01*
Y133581D01*
X127746D01*
Y162005D01*
X127609D01*
Y163241D01*
X127471D01*
Y163928D01*
X127334D01*
Y164477D01*
X127197D01*
Y164752D01*
X127059D01*
Y165163D01*
X126922D01*
Y165438D01*
X126785D01*
Y165713D01*
X126647D01*
Y165987D01*
X126510D01*
Y166262D01*
X126373D01*
Y166537D01*
X126236D01*
Y166674D01*
X126098D01*
Y166949D01*
X125961D01*
Y167086D01*
X125823D01*
Y167223D01*
X125686D01*
Y167498D01*
X125549D01*
Y167635D01*
X125412D01*
Y167773D01*
X125274D01*
Y167910D01*
X125137D01*
Y168047D01*
X125000D01*
Y168185D01*
X124862D01*
Y168322D01*
X124725D01*
Y168459D01*
X124588D01*
Y168596D01*
X124450D01*
Y168734D01*
X124176D01*
Y168871D01*
X124038D01*
Y169008D01*
X123901D01*
Y169146D01*
X123626D01*
Y169283D01*
X123489D01*
Y169420D01*
X123215D01*
Y169558D01*
X122940D01*
Y169695D01*
X122665D01*
Y169832D01*
X122391D01*
Y169970D01*
X122116D01*
Y170107D01*
X121704D01*
Y170244D01*
X121292D01*
Y170382D01*
X120880D01*
Y170519D01*
X120194D01*
Y170656D01*
X117310D01*
Y170519D01*
X116623D01*
Y170382D01*
X116211D01*
Y170244D01*
X115799D01*
Y170107D01*
X115387D01*
Y169970D01*
X115113D01*
Y169832D01*
X114838D01*
Y169695D01*
X114564D01*
Y169558D01*
X114289D01*
Y169420D01*
X114151D01*
Y169283D01*
X113877D01*
Y169146D01*
X113740D01*
Y169008D01*
X113465D01*
Y168871D01*
X113328D01*
Y168734D01*
X113190D01*
Y168596D01*
X113053D01*
Y168459D01*
X112778D01*
Y168322D01*
X112641D01*
Y168185D01*
X112504D01*
Y168047D01*
X112366D01*
Y167910D01*
X112229D01*
Y167773D01*
X112092D01*
Y167498D01*
X111954D01*
Y167361D01*
X111817D01*
Y167223D01*
X111680D01*
Y167086D01*
X111543D01*
Y166811D01*
X111405D01*
Y166674D01*
X111268D01*
Y166399D01*
X111131D01*
Y166125D01*
X110993D01*
Y165987D01*
X110856D01*
Y165713D01*
X110719D01*
Y165438D01*
X110581D01*
Y165026D01*
X110444D01*
Y164752D01*
X110307D01*
Y164340D01*
X110169D01*
Y163790D01*
X110032D01*
Y163104D01*
X109895D01*
Y161731D01*
X109757D01*
Y161593D01*
X109895D01*
Y120398D01*
X109757D01*
Y120261D01*
X109895D01*
Y119986D01*
X109757D01*
Y119025D01*
X109620D01*
Y118338D01*
X109483D01*
Y117926D01*
X109345D01*
Y117514D01*
X109208D01*
Y117102D01*
X109071D01*
Y116828D01*
X108933D01*
Y116553D01*
X108796D01*
Y116278D01*
X108659D01*
Y116004D01*
X108521D01*
Y115866D01*
X108384D01*
Y115592D01*
X108247D01*
Y115455D01*
X108110D01*
Y115180D01*
X107972D01*
Y115043D01*
X107835D01*
Y114905D01*
X107698D01*
Y114631D01*
X107560D01*
Y114493D01*
X107423D01*
Y114356D01*
X107286D01*
Y114219D01*
X107148D01*
Y114081D01*
X107011D01*
Y113944D01*
X106874D01*
Y113807D01*
X106736D01*
Y113669D01*
X106462D01*
Y113532D01*
X106324D01*
Y113395D01*
X106187D01*
Y113258D01*
X106050D01*
Y113120D01*
X105775D01*
Y112983D01*
X105638D01*
Y112845D01*
X105363D01*
Y112708D01*
X105089D01*
Y112571D01*
X104814D01*
Y112434D01*
X104539D01*
Y112296D01*
X104265D01*
Y112159D01*
X103853D01*
Y112022D01*
X103441D01*
Y111884D01*
X103029D01*
Y111747D01*
X102342D01*
Y111610D01*
X99459D01*
Y111747D01*
X98772D01*
Y111884D01*
X98223D01*
Y112022D01*
X97811D01*
Y112159D01*
X97536D01*
Y112296D01*
X97124D01*
Y112434D01*
X96849D01*
Y112571D01*
X96575D01*
Y112708D01*
X96438D01*
Y112845D01*
X96163D01*
Y112983D01*
X95888D01*
Y113120D01*
X95751D01*
Y113258D01*
X95614D01*
Y113395D01*
X95339D01*
Y113532D01*
X95202D01*
Y113669D01*
X95064D01*
Y113807D01*
X94927D01*
Y113944D01*
X94790D01*
Y114081D01*
X94652D01*
Y114219D01*
X94515D01*
Y114356D01*
X94378D01*
Y114493D01*
X94241D01*
Y114631D01*
X94103D01*
Y114768D01*
X93966D01*
Y114905D01*
X93828D01*
Y115180D01*
X93691D01*
Y115317D01*
X93554D01*
Y115455D01*
X93417D01*
Y115729D01*
X93279D01*
Y115866D01*
X93142D01*
Y116141D01*
X93005D01*
Y116416D01*
X92867D01*
Y116690D01*
X92730D01*
Y116965D01*
X92593D01*
Y117377D01*
X92455D01*
Y117789D01*
X92318D01*
Y118201D01*
X92181D01*
Y118750D01*
X92043D01*
Y119437D01*
X91906D01*
Y145802D01*
X91769D01*
Y146763D01*
X91631D01*
Y147312D01*
X91494D01*
Y147724D01*
X91357D01*
Y148136D01*
X91220D01*
Y148411D01*
X91082D01*
Y148823D01*
X90945D01*
Y149097D01*
X90808D01*
Y149235D01*
X90670D01*
Y149509D01*
X90533D01*
Y149784D01*
X90396D01*
Y149921D01*
X90258D01*
Y150196D01*
X90121D01*
Y150333D01*
X89984D01*
Y150471D01*
X89846D01*
Y150745D01*
X89709D01*
Y150883D01*
X89572D01*
Y151020D01*
X89434D01*
Y151157D01*
X89297D01*
Y151294D01*
X89160D01*
Y151432D01*
X89022D01*
Y151569D01*
X88885D01*
Y151706D01*
X88748D01*
Y151844D01*
X88610D01*
Y151981D01*
X88336D01*
Y152118D01*
X88198D01*
Y152256D01*
X88061D01*
Y152393D01*
X87787D01*
Y152530D01*
X87649D01*
Y152668D01*
X87375D01*
Y152805D01*
X87100D01*
Y152942D01*
X86825D01*
Y153080D01*
X86551D01*
Y153217D01*
X86276D01*
Y153354D01*
X85864D01*
Y153491D01*
X85452D01*
Y153629D01*
X84903D01*
Y153766D01*
X84079D01*
Y153904D01*
X81882D01*
Y153766D01*
X81058D01*
Y153629D01*
X80509D01*
Y153491D01*
X80097D01*
Y153354D01*
X79685D01*
Y153217D01*
X79410D01*
Y153080D01*
X79136D01*
Y152942D01*
X78861D01*
Y152805D01*
X78586D01*
Y152668D01*
X78312D01*
Y152530D01*
X78174D01*
Y152393D01*
X77900D01*
Y152256D01*
X77762D01*
Y152118D01*
X77488D01*
Y151981D01*
X77350D01*
Y151844D01*
X77213D01*
Y151706D01*
X77076D01*
Y151569D01*
X76939D01*
Y151432D01*
X76801D01*
Y151294D01*
X76664D01*
Y151157D01*
X76526D01*
Y151020D01*
X76389D01*
Y150883D01*
X76252D01*
Y150745D01*
X76115D01*
Y150608D01*
X75977D01*
Y150333D01*
X75840D01*
Y150196D01*
X75703D01*
Y150059D01*
X75565D01*
Y149784D01*
X75428D01*
Y149647D01*
X75291D01*
Y149372D01*
X75153D01*
Y149097D01*
X75016D01*
Y148823D01*
X74879D01*
Y148548D01*
X74741D01*
Y148136D01*
X74604D01*
Y147861D01*
X74467D01*
Y147312D01*
X74329D01*
Y146763D01*
X74192D01*
Y145939D01*
X74055D01*
Y74671D01*
X73917D01*
Y73847D01*
X73780D01*
Y73298D01*
X73643D01*
Y72886D01*
X73506D01*
Y72474D01*
X73368D01*
Y72200D01*
X73231D01*
Y71925D01*
X73094D01*
Y71513D01*
X72956D01*
Y71376D01*
X72819D01*
Y71101D01*
X72682D01*
Y70826D01*
X72544D01*
Y70689D01*
X72407D01*
Y70414D01*
X72270D01*
Y70277D01*
X72132D01*
Y70140D01*
X71995D01*
Y69865D01*
X71858D01*
Y69728D01*
X71720D01*
Y69591D01*
X71583D01*
Y69453D01*
X71446D01*
Y69316D01*
X71308D01*
Y69179D01*
X71171D01*
Y69041D01*
X71034D01*
Y68904D01*
X70897D01*
Y68767D01*
X70622D01*
Y68629D01*
X70485D01*
Y68492D01*
X70347D01*
Y68355D01*
X70210D01*
Y68217D01*
X69935D01*
Y68080D01*
X69798D01*
Y67943D01*
X69523D01*
Y67805D01*
X69249D01*
Y67668D01*
X68974D01*
Y67531D01*
X68699D01*
Y67393D01*
X68425D01*
Y67256D01*
X68013D01*
Y67119D01*
X67601D01*
Y66982D01*
X67052D01*
Y66844D01*
X66365D01*
Y66707D01*
X63756D01*
Y66844D01*
X63069D01*
Y66982D01*
X62520D01*
Y67119D01*
X62108D01*
Y67256D01*
X61834D01*
Y67393D01*
X61422D01*
Y67531D01*
X61147D01*
Y67668D01*
X60872D01*
Y67805D01*
X60598D01*
Y67943D01*
X60460D01*
Y68080D01*
X60186D01*
Y68217D01*
X60048D01*
Y68355D01*
X59774D01*
Y68492D01*
X59637D01*
Y68629D01*
X59499D01*
Y68767D01*
X59362D01*
Y68904D01*
X59087D01*
Y69041D01*
X58950D01*
Y69179D01*
X58813D01*
Y69316D01*
X58675D01*
Y69453D01*
X58538D01*
Y69591D01*
X58401D01*
Y69865D01*
X58263D01*
Y70002D01*
X58126D01*
Y70140D01*
X57989D01*
Y70277D01*
X57851D01*
Y70552D01*
X57714D01*
Y70689D01*
X57577D01*
Y70964D01*
X57439D01*
Y71101D01*
X57302D01*
Y71376D01*
X57165D01*
Y71650D01*
X57027D01*
Y71925D01*
X56890D01*
Y72200D01*
X56753D01*
Y72611D01*
X56616D01*
Y73024D01*
X56478D01*
Y73435D01*
X56341D01*
Y73985D01*
X56203D01*
Y74946D01*
X56066D01*
Y75083D01*
X56203D01*
Y75220D01*
X56066D01*
Y183839D01*
X55929D01*
Y184525D01*
X55792D01*
Y185075D01*
X55654D01*
Y185487D01*
X55517D01*
Y185898D01*
X55380D01*
Y186173D01*
X55242D01*
Y186448D01*
X55105D01*
Y186722D01*
X54968D01*
Y186997D01*
X54830D01*
Y187272D01*
X54693D01*
Y187409D01*
X54556D01*
Y187684D01*
X54418D01*
Y187821D01*
X54281D01*
Y188095D01*
X54144D01*
Y188233D01*
X54007D01*
Y188370D01*
X53869D01*
Y188507D01*
X53732D01*
Y188645D01*
X53594D01*
Y188782D01*
X53457D01*
Y188919D01*
X53320D01*
Y189057D01*
X53183D01*
Y189194D01*
X53045D01*
Y189331D01*
X52908D01*
Y189469D01*
X52771D01*
Y189606D01*
X52633D01*
Y189743D01*
X52359D01*
Y189881D01*
X52221D01*
Y190018D01*
X51947D01*
Y190155D01*
X51809D01*
Y190293D01*
X51535D01*
Y190430D01*
X51260D01*
Y190567D01*
X50985D01*
Y190705D01*
X50711D01*
Y190842D01*
X50436D01*
Y190979D01*
X50024D01*
Y191117D01*
X49612D01*
Y191254D01*
X49063D01*
Y191391D01*
X48239D01*
Y191528D01*
X46042D01*
Y191391D01*
X45218D01*
Y191254D01*
X44669D01*
Y191117D01*
X44257D01*
Y190979D01*
X43982D01*
Y190842D01*
X43570D01*
Y190705D01*
X43296D01*
Y190567D01*
X43021D01*
Y190430D01*
X42746D01*
Y190293D01*
X42609D01*
Y190155D01*
X42334D01*
Y190018D01*
X42197D01*
Y189881D01*
X41922D01*
Y189743D01*
X41785D01*
Y189606D01*
X41648D01*
Y189469D01*
X41373D01*
Y189331D01*
X41236D01*
Y189194D01*
X41099D01*
Y189057D01*
X40961D01*
Y188919D01*
X40824D01*
Y188782D01*
X40687D01*
Y188645D01*
X40549D01*
Y188507D01*
X40412D01*
Y188233D01*
X40275D01*
Y188095D01*
X40137D01*
Y187958D01*
X40000D01*
Y187821D01*
X39863D01*
Y187546D01*
X39725D01*
Y187272D01*
X39588D01*
Y187134D01*
X39451D01*
Y186860D01*
X39313D01*
Y186585D01*
X39176D01*
Y186310D01*
X39039D01*
Y186036D01*
X38902D01*
Y185624D01*
X38764D01*
Y185349D01*
X38627D01*
Y184800D01*
X38490D01*
Y184251D01*
X38352D01*
Y183152D01*
X38215D01*
Y162417D01*
X38078D01*
Y161593D01*
X37940D01*
Y161181D01*
X37803D01*
Y160632D01*
X37666D01*
Y160357D01*
X37528D01*
Y159945D01*
X37391D01*
Y159671D01*
X37254D01*
Y159396D01*
X37116D01*
Y159122D01*
X36979D01*
Y158984D01*
X36842D01*
Y158710D01*
X36704D01*
Y158572D01*
X36567D01*
Y158298D01*
X36430D01*
Y158160D01*
X36293D01*
Y158023D01*
X36155D01*
Y157748D01*
X36018D01*
Y157611D01*
X35880D01*
Y157474D01*
X35743D01*
Y157336D01*
X35606D01*
Y157199D01*
X35469D01*
Y157062D01*
X35331D01*
Y156924D01*
X35194D01*
Y156787D01*
X35057D01*
Y156650D01*
X34782D01*
Y156512D01*
X34645D01*
Y156375D01*
X34507D01*
Y156238D01*
X34233D01*
Y156101D01*
X34095D01*
Y155963D01*
X33821D01*
Y155826D01*
X33684D01*
Y155689D01*
X33409D01*
Y155551D01*
X33134D01*
Y155414D01*
X32860D01*
Y155277D01*
X32448D01*
Y155139D01*
X32036D01*
Y155002D01*
X31624D01*
Y154865D01*
X31074D01*
Y154727D01*
X30113D01*
Y154590D01*
X29976D01*
Y154727D01*
X29839D01*
Y154590D01*
X28328D01*
Y154727D01*
X27504D01*
Y154865D01*
X26955D01*
Y155002D01*
X26543D01*
Y155139D01*
X26131D01*
Y155277D01*
X25719D01*
Y155414D01*
X25444D01*
Y155551D01*
X25170D01*
Y155689D01*
X24895D01*
Y155826D01*
X24758D01*
Y155963D01*
X24483D01*
Y156101D01*
X24209D01*
Y156238D01*
X24071D01*
Y156375D01*
X23934D01*
Y156512D01*
X23659D01*
Y156650D01*
X23522D01*
Y156787D01*
X23385D01*
Y156924D01*
X23247D01*
Y157062D01*
X23110D01*
Y157199D01*
X22973D01*
Y157336D01*
X22835D01*
Y157474D01*
X22698D01*
Y157611D01*
X22561D01*
Y157748D01*
X22423D01*
Y157886D01*
X22286D01*
Y158160D01*
X22149D01*
Y158298D01*
X22011D01*
Y158435D01*
X21874D01*
Y158710D01*
X21737D01*
Y158847D01*
X21600D01*
Y159122D01*
X21462D01*
Y159396D01*
X21325D01*
Y159671D01*
X21188D01*
Y159945D01*
X21050D01*
Y160220D01*
X20913D01*
Y160632D01*
X20776D01*
Y161044D01*
X20638D01*
Y161593D01*
X20501D01*
Y162143D01*
X20364D01*
Y163653D01*
X20226D01*
Y336948D01*
X20364D01*
Y337085D01*
X75153D01*
Y323765D01*
X90258D01*
Y336948D01*
X90396D01*
Y337085D01*
X93691D01*
Y323765D01*
X108933D01*
Y337085D01*
X112229D01*
Y336948D01*
X112366D01*
Y323765D01*
X127471D01*
Y337085D01*
X130904D01*
Y323765D01*
X146009D01*
Y337085D01*
X158368D01*
Y316625D01*
D02*
G37*
G36*
X30250Y141819D02*
X30937D01*
Y141682D01*
X31624D01*
Y141545D01*
X32036D01*
Y141408D01*
X32448D01*
Y141270D01*
X32860D01*
Y141133D01*
X33134D01*
Y140996D01*
X33409D01*
Y140858D01*
X33684D01*
Y140721D01*
X33821D01*
Y140584D01*
X34095D01*
Y140446D01*
X34370D01*
Y140309D01*
X34507D01*
Y140172D01*
X34645D01*
Y140034D01*
X34919D01*
Y139897D01*
X35057D01*
Y139760D01*
X35194D01*
Y139622D01*
X35331D01*
Y139485D01*
X35469D01*
Y139348D01*
X35606D01*
Y139211D01*
X35743D01*
Y139073D01*
X35880D01*
Y138936D01*
X36018D01*
Y138799D01*
X36155D01*
Y138661D01*
X36293D01*
Y138524D01*
X36430D01*
Y138249D01*
X36567D01*
Y138112D01*
X36704D01*
Y137837D01*
X36842D01*
Y137700D01*
X36979D01*
Y137425D01*
X37116D01*
Y137151D01*
X37254D01*
Y137013D01*
X37391D01*
Y136601D01*
X37528D01*
Y136327D01*
X37666D01*
Y135915D01*
X37803D01*
Y135503D01*
X37940D01*
Y135091D01*
X38078D01*
Y134404D01*
X38215D01*
Y121085D01*
X38078D01*
Y120398D01*
X37940D01*
Y119849D01*
X37803D01*
Y119437D01*
X37666D01*
Y119025D01*
X37528D01*
Y118750D01*
X37391D01*
Y118476D01*
X37254D01*
Y118201D01*
X37116D01*
Y117926D01*
X36979D01*
Y117652D01*
X36842D01*
Y117514D01*
X36704D01*
Y117240D01*
X36567D01*
Y117102D01*
X36430D01*
Y116965D01*
X36293D01*
Y116828D01*
X36155D01*
Y116553D01*
X36018D01*
Y116416D01*
X35880D01*
Y116278D01*
X35743D01*
Y116141D01*
X35606D01*
Y116004D01*
X35469D01*
Y115866D01*
X35331D01*
Y115729D01*
X35194D01*
Y115592D01*
X35057D01*
Y115455D01*
X34782D01*
Y115317D01*
X34645D01*
Y115180D01*
X34507D01*
Y115043D01*
X34233D01*
Y114905D01*
X34095D01*
Y114768D01*
X33821D01*
Y114631D01*
X33546D01*
Y114493D01*
X33272D01*
Y114356D01*
X32997D01*
Y114219D01*
X32722D01*
Y114081D01*
X32310D01*
Y113944D01*
X31898D01*
Y113807D01*
X31486D01*
Y113669D01*
X30800D01*
Y113532D01*
X29564D01*
Y113395D01*
X29015D01*
Y113532D01*
X27641D01*
Y113669D01*
X27092D01*
Y113807D01*
X26543D01*
Y113944D01*
X26131D01*
Y114081D01*
X25856D01*
Y114219D01*
X25444D01*
Y114356D01*
X25170D01*
Y114493D01*
X25032D01*
Y114631D01*
X24758D01*
Y114768D01*
X24483D01*
Y114905D01*
X24346D01*
Y115043D01*
X24071D01*
Y115180D01*
X23934D01*
Y115317D01*
X23659D01*
Y115455D01*
X23522D01*
Y115592D01*
X23385D01*
Y115729D01*
X23247D01*
Y115866D01*
X23110D01*
Y116004D01*
X22973D01*
Y116141D01*
X22835D01*
Y116278D01*
X22698D01*
Y116416D01*
X22561D01*
Y116553D01*
X22423D01*
Y116690D01*
X22286D01*
Y116828D01*
X22149D01*
Y117102D01*
X22011D01*
Y117240D01*
X21874D01*
Y117514D01*
X21737D01*
Y117652D01*
X21600D01*
Y117926D01*
X21462D01*
Y118201D01*
X21325D01*
Y118338D01*
X21188D01*
Y118750D01*
X21050D01*
Y119025D01*
X20913D01*
Y119437D01*
X20776D01*
Y119711D01*
X20638D01*
Y120261D01*
X20501D01*
Y120947D01*
X20364D01*
Y122320D01*
X20226D01*
Y122458D01*
X20364D01*
Y122595D01*
X20226D01*
Y133031D01*
X20364D01*
Y134542D01*
X20501D01*
Y135091D01*
X20638D01*
Y135640D01*
X20776D01*
Y136052D01*
X20913D01*
Y136327D01*
X21050D01*
Y136739D01*
X21188D01*
Y137013D01*
X21325D01*
Y137288D01*
X21462D01*
Y137563D01*
X21600D01*
Y137700D01*
X21737D01*
Y137975D01*
X21874D01*
Y138112D01*
X22011D01*
Y138387D01*
X22149D01*
Y138524D01*
X22286D01*
Y138661D01*
X22423D01*
Y138799D01*
X22561D01*
Y138936D01*
X22698D01*
Y139073D01*
X22835D01*
Y139211D01*
X22973D01*
Y139348D01*
X23110D01*
Y139485D01*
X23247D01*
Y139622D01*
X23385D01*
Y139760D01*
X23522D01*
Y139897D01*
X23659D01*
Y140034D01*
X23797D01*
Y140172D01*
X24071D01*
Y140309D01*
X24209D01*
Y140446D01*
X24483D01*
Y140584D01*
X24620D01*
Y140721D01*
X24895D01*
Y140858D01*
X25170D01*
Y140996D01*
X25444D01*
Y141133D01*
X25719D01*
Y141270D01*
X26131D01*
Y141408D01*
X26406D01*
Y141545D01*
X26955D01*
Y141682D01*
X27504D01*
Y141819D01*
X28465D01*
Y141957D01*
X30250D01*
Y141819D01*
D02*
G37*
G36*
X102205Y100899D02*
X102892D01*
Y100762D01*
X103441D01*
Y100624D01*
X103853D01*
Y100487D01*
X104127D01*
Y100350D01*
X104539D01*
Y100212D01*
X104814D01*
Y100075D01*
X105089D01*
Y99938D01*
X105226D01*
Y99800D01*
X105500D01*
Y99663D01*
X105775D01*
Y99526D01*
X105913D01*
Y99388D01*
X106187D01*
Y99251D01*
X106324D01*
Y99114D01*
X106462D01*
Y98976D01*
X106599D01*
Y98839D01*
X106874D01*
Y98702D01*
X107011D01*
Y98565D01*
X107148D01*
Y98427D01*
X107286D01*
Y98290D01*
X107423D01*
Y98153D01*
X107560D01*
Y97878D01*
X107698D01*
Y97741D01*
X107835D01*
Y97603D01*
X107972D01*
Y97466D01*
X108110D01*
Y97191D01*
X108247D01*
Y97054D01*
X108384D01*
Y96779D01*
X108521D01*
Y96642D01*
X108659D01*
Y96367D01*
X108796D01*
Y96093D01*
X108933D01*
Y95818D01*
X109071D01*
Y95543D01*
X109208D01*
Y95132D01*
X109345D01*
Y94720D01*
X109483D01*
Y94308D01*
X109620D01*
Y93621D01*
X109757D01*
Y92660D01*
X109895D01*
Y91699D01*
X109757D01*
Y91561D01*
X109895D01*
Y91424D01*
X109757D01*
Y91287D01*
X109895D01*
Y91149D01*
X109757D01*
Y90325D01*
X109620D01*
Y89639D01*
X109483D01*
Y89090D01*
X109345D01*
Y88678D01*
X109208D01*
Y88403D01*
X109071D01*
Y87991D01*
X108933D01*
Y87716D01*
X108796D01*
Y87442D01*
X108659D01*
Y87304D01*
X108521D01*
Y87030D01*
X108384D01*
Y86755D01*
X108247D01*
Y86618D01*
X108110D01*
Y86481D01*
X107972D01*
Y86206D01*
X107835D01*
Y86069D01*
X107698D01*
Y85931D01*
X107560D01*
Y85794D01*
X107423D01*
Y85657D01*
X107286D01*
Y85519D01*
X107148D01*
Y85382D01*
X107011D01*
Y85245D01*
X106874D01*
Y85107D01*
X106736D01*
Y84970D01*
X106599D01*
Y84833D01*
X106462D01*
Y84695D01*
X106324D01*
Y84558D01*
X106050D01*
Y84421D01*
X105913D01*
Y84284D01*
X105638D01*
Y84146D01*
X105500D01*
Y84009D01*
X105226D01*
Y83871D01*
X104951D01*
Y83734D01*
X104677D01*
Y83597D01*
X104402D01*
Y83460D01*
X104127D01*
Y83322D01*
X103715D01*
Y83185D01*
X103303D01*
Y83048D01*
X102754D01*
Y82910D01*
X101930D01*
Y82773D01*
X99871D01*
Y82910D01*
X99047D01*
Y83048D01*
X98497D01*
Y83185D01*
X98085D01*
Y83322D01*
X97673D01*
Y83460D01*
X97399D01*
Y83597D01*
X96987D01*
Y83734D01*
X96712D01*
Y83871D01*
X96575D01*
Y84009D01*
X96300D01*
Y84146D01*
X96026D01*
Y84284D01*
X95888D01*
Y84421D01*
X95614D01*
Y84558D01*
X95476D01*
Y84695D01*
X95339D01*
Y84833D01*
X95064D01*
Y84970D01*
X94927D01*
Y85107D01*
X94790D01*
Y85245D01*
X94652D01*
Y85382D01*
X94515D01*
Y85519D01*
X94378D01*
Y85657D01*
X94241D01*
Y85794D01*
X94103D01*
Y86069D01*
X93966D01*
Y86206D01*
X93828D01*
Y86343D01*
X93691D01*
Y86481D01*
X93554D01*
Y86755D01*
X93417D01*
Y86892D01*
X93279D01*
Y87167D01*
X93142D01*
Y87442D01*
X93005D01*
Y87579D01*
X92867D01*
Y87854D01*
X92730D01*
Y88266D01*
X92593D01*
Y88540D01*
X92455D01*
Y88952D01*
X92318D01*
Y89364D01*
X92181D01*
Y89914D01*
X92043D01*
Y90737D01*
X91906D01*
Y93209D01*
X92043D01*
Y93896D01*
X92181D01*
Y94445D01*
X92318D01*
Y94857D01*
X92455D01*
Y95269D01*
X92593D01*
Y95681D01*
X92730D01*
Y95955D01*
X92867D01*
Y96230D01*
X93005D01*
Y96505D01*
X93142D01*
Y96642D01*
X93279D01*
Y96917D01*
X93417D01*
Y97054D01*
X93554D01*
Y97329D01*
X93691D01*
Y97466D01*
X93828D01*
Y97741D01*
X93966D01*
Y97878D01*
X94103D01*
Y98015D01*
X94241D01*
Y98153D01*
X94378D01*
Y98290D01*
X94515D01*
Y98427D01*
X94652D01*
Y98565D01*
X94790D01*
Y98702D01*
X94927D01*
Y98839D01*
X95064D01*
Y98976D01*
X95202D01*
Y99114D01*
X95476D01*
Y99251D01*
X95614D01*
Y99388D01*
X95751D01*
Y99526D01*
X96026D01*
Y99663D01*
X96163D01*
Y99800D01*
X96438D01*
Y99938D01*
X96712D01*
Y100075D01*
X96987D01*
Y100212D01*
X97261D01*
Y100350D01*
X97536D01*
Y100487D01*
X97948D01*
Y100624D01*
X98360D01*
Y100762D01*
X98909D01*
Y100899D01*
X99596D01*
Y101036D01*
X102205D01*
Y100899D01*
D02*
G37*
G36*
X206589Y301958D02*
X206829Y301915D01*
X207041Y301887D01*
X207238Y301831D01*
X207407Y301775D01*
X207576Y301718D01*
X207717Y301662D01*
X207844Y301591D01*
X207957Y301535D01*
X208055Y301478D01*
X208126Y301422D01*
X208182Y301380D01*
X208239Y301352D01*
X208253Y301337D01*
X208267Y301323D01*
X208394Y301182D01*
X208507Y301041D01*
X208605Y300886D01*
X208690Y300717D01*
X208817Y300393D01*
X208901Y300083D01*
X208958Y299787D01*
X208972Y299674D01*
X208986Y299561D01*
X209000Y299477D01*
Y299350D01*
X208986Y299040D01*
X208944Y298758D01*
X208887Y298504D01*
X208817Y298278D01*
X208760Y298095D01*
X208704Y297968D01*
X208662Y297884D01*
X208648Y297855D01*
X208507Y297630D01*
X208337Y297433D01*
X208168Y297278D01*
X208013Y297136D01*
X207858Y297038D01*
X207745Y296967D01*
X207661Y296925D01*
X207647Y296911D01*
X207633D01*
X207351Y296812D01*
X207055Y296728D01*
X206730Y296671D01*
X206420Y296643D01*
X206152Y296615D01*
X206040D01*
X205927Y296601D01*
X205842D01*
X205786D01*
X205744D01*
X205730D01*
X199076D01*
Y297898D01*
X205800D01*
X206096D01*
X206350Y297926D01*
X206561Y297940D01*
X206730Y297968D01*
X206857Y297997D01*
X206956Y298011D01*
X207012Y298039D01*
X207026D01*
X207167Y298095D01*
X207280Y298166D01*
X207379Y298250D01*
X207477Y298321D01*
X207534Y298405D01*
X207590Y298462D01*
X207619Y298504D01*
X207633Y298518D01*
X207703Y298659D01*
X207759Y298800D01*
X207788Y298941D01*
X207816Y299068D01*
X207830Y299195D01*
X207844Y299279D01*
Y299364D01*
X207830Y299589D01*
X207773Y299801D01*
X207717Y299970D01*
X207633Y300125D01*
X207562Y300238D01*
X207492Y300322D01*
X207449Y300379D01*
X207435Y300393D01*
X207351Y300463D01*
X207252Y300520D01*
X207026Y300604D01*
X206773Y300689D01*
X206519Y300731D01*
X206279Y300774D01*
X206181D01*
X206096Y300788D01*
X206011Y300802D01*
X205955D01*
X205927D01*
X205913D01*
X206082Y301972D01*
X206350D01*
X206589Y301958D01*
D02*
G37*
G36*
X196800Y300633D02*
X193840Y299575D01*
Y295487D01*
X196800Y294345D01*
Y292879D01*
X187045Y296869D01*
Y298278D01*
X196800Y302000D01*
Y300633D01*
D02*
G37*
G36*
X206646Y294655D02*
X206829Y294641D01*
X206998Y294627D01*
X207111D01*
X207196Y294613D01*
X207252Y294599D01*
X207266D01*
X207449Y294557D01*
X207619Y294500D01*
X207773Y294444D01*
X207900Y294373D01*
X208013Y294317D01*
X208084Y294275D01*
X208140Y294247D01*
X208154Y294233D01*
X208281Y294120D01*
X208394Y293993D01*
X208493Y293866D01*
X208577Y293725D01*
X208648Y293612D01*
X208704Y293514D01*
X208732Y293457D01*
X208746Y293429D01*
X208831Y293218D01*
X208887Y293020D01*
X208930Y292823D01*
X208958Y292640D01*
X208972Y292484D01*
X208986Y292358D01*
Y292259D01*
X208972Y292005D01*
X208930Y291751D01*
X208873Y291526D01*
X208803Y291300D01*
X208704Y291103D01*
X208605Y290920D01*
X208507Y290751D01*
X208394Y290595D01*
X208281Y290455D01*
X208182Y290342D01*
X208070Y290243D01*
X207985Y290159D01*
X207915Y290088D01*
X207858Y290046D01*
X207816Y290018D01*
X207802Y290004D01*
X208831D01*
Y288932D01*
X201754D01*
Y290130D01*
X205546D01*
X205870Y290144D01*
X206152Y290159D01*
X206392Y290187D01*
X206589Y290229D01*
X206744Y290271D01*
X206857Y290299D01*
X206914Y290314D01*
X206942Y290328D01*
X207111Y290412D01*
X207252Y290511D01*
X207379Y290624D01*
X207492Y290737D01*
X207576Y290835D01*
X207633Y290920D01*
X207675Y290976D01*
X207689Y291004D01*
X207773Y291188D01*
X207844Y291371D01*
X207886Y291540D01*
X207929Y291695D01*
X207943Y291822D01*
X207957Y291921D01*
Y292019D01*
X207943Y292217D01*
X207915Y292386D01*
X207872Y292541D01*
X207816Y292668D01*
X207773Y292781D01*
X207731Y292851D01*
X207703Y292907D01*
X207689Y292922D01*
X207576Y293048D01*
X207463Y293147D01*
X207337Y293232D01*
X207224Y293302D01*
X207111Y293344D01*
X207026Y293373D01*
X206970Y293401D01*
X206956D01*
X206801Y293429D01*
X206618Y293443D01*
X206406Y293457D01*
X206195D01*
X205997Y293471D01*
X205842D01*
X205772D01*
X205730D01*
X205701D01*
X205687D01*
X201754D01*
Y294670D01*
X206138D01*
X206406D01*
X206646Y294655D01*
D02*
G37*
G36*
X196800Y290807D02*
X193107D01*
X192825Y290793D01*
X192571Y290779D01*
X192332Y290751D01*
X192120Y290708D01*
X191951Y290666D01*
X191824Y290638D01*
X191740Y290624D01*
X191711Y290610D01*
X191556Y290553D01*
X191430Y290483D01*
X191317Y290412D01*
X191218Y290342D01*
X191147Y290271D01*
X191091Y290229D01*
X191063Y290187D01*
X191049Y290173D01*
X190964Y290060D01*
X190908Y289933D01*
X190866Y289806D01*
X190837Y289707D01*
X190823Y289609D01*
X190809Y289538D01*
Y289468D01*
X190823Y289313D01*
X190851Y289158D01*
X190894Y289003D01*
X190936Y288876D01*
X190978Y288763D01*
X191021Y288678D01*
X191049Y288622D01*
X191063Y288608D01*
X189963Y288171D01*
X189837Y288410D01*
X189738Y288636D01*
X189667Y288833D01*
X189611Y289017D01*
X189583Y289172D01*
X189569Y289299D01*
Y289397D01*
X189583Y289552D01*
X189611Y289693D01*
X189653Y289834D01*
X189696Y289947D01*
X189738Y290032D01*
X189780Y290116D01*
X189808Y290159D01*
X189822Y290173D01*
X189935Y290299D01*
X190076Y290426D01*
X190245Y290553D01*
X190400Y290666D01*
X190555Y290779D01*
X190682Y290849D01*
X190781Y290906D01*
X190795Y290920D01*
X189724D01*
Y292005D01*
X196800D01*
Y290807D01*
D02*
G37*
G36*
X208831Y285887D02*
X199076D01*
Y287085D01*
X208831D01*
Y285887D01*
D02*
G37*
G36*
Y282828D02*
X201754D01*
Y284026D01*
X208831D01*
Y282828D01*
D02*
G37*
G36*
X200443D02*
X199076D01*
Y284026D01*
X200443D01*
Y282828D01*
D02*
G37*
G36*
X196800Y286268D02*
X193135D01*
X192797Y286254D01*
X192501Y286240D01*
X192247Y286211D01*
X192036Y286169D01*
X191881Y286127D01*
X191768Y286099D01*
X191697Y286084D01*
X191669Y286070D01*
X191486Y285986D01*
X191331Y285887D01*
X191190Y285788D01*
X191077Y285690D01*
X190993Y285591D01*
X190936Y285521D01*
X190894Y285464D01*
X190880Y285450D01*
X190795Y285281D01*
X190725Y285126D01*
X190682Y284957D01*
X190640Y284816D01*
X190626Y284703D01*
X190612Y284604D01*
Y284520D01*
X190626Y284280D01*
X190668Y284083D01*
X190739Y283914D01*
X190809Y283787D01*
X190894Y283688D01*
X190950Y283617D01*
X191007Y283575D01*
X191021Y283561D01*
X191190Y283463D01*
X191373Y283392D01*
X191570Y283336D01*
X191768Y283307D01*
X191937Y283279D01*
X192092Y283265D01*
X192148D01*
X192177D01*
X192205D01*
X192219D01*
X196800D01*
Y282067D01*
X192698D01*
X192318Y282039D01*
X191993Y281982D01*
X191726Y281912D01*
X191500Y281813D01*
X191331Y281728D01*
X191218Y281644D01*
X191147Y281588D01*
X191119Y281574D01*
X190950Y281376D01*
X190823Y281165D01*
X190739Y280953D01*
X190668Y280756D01*
X190640Y280587D01*
X190626Y280446D01*
X190612Y280389D01*
Y280319D01*
X190626Y280164D01*
X190640Y280037D01*
X190668Y279910D01*
X190711Y279811D01*
X190753Y279713D01*
X190781Y279656D01*
X190795Y279614D01*
X190809Y279600D01*
X190894Y279487D01*
X190978Y279403D01*
X191063Y279332D01*
X191147Y279276D01*
X191218Y279233D01*
X191274Y279205D01*
X191317Y279177D01*
X191331D01*
X191458Y279135D01*
X191627Y279107D01*
X191796Y279092D01*
X191965Y279078D01*
X192120Y279064D01*
X192247D01*
X192332D01*
X192346D01*
X192360D01*
X196800D01*
Y277866D01*
X191951D01*
X191726D01*
X191528Y277894D01*
X191331Y277922D01*
X191162Y277950D01*
X190993Y277993D01*
X190851Y278049D01*
X190725Y278092D01*
X190598Y278148D01*
X190499Y278204D01*
X190400Y278247D01*
X190273Y278345D01*
X190189Y278402D01*
X190161Y278430D01*
X189963Y278655D01*
X189822Y278923D01*
X189710Y279191D01*
X189639Y279445D01*
X189597Y279685D01*
X189583Y279783D01*
Y279882D01*
X189569Y279952D01*
Y280051D01*
X189583Y280305D01*
X189625Y280530D01*
X189681Y280756D01*
X189766Y280967D01*
X189865Y281165D01*
X189963Y281348D01*
X190076Y281503D01*
X190189Y281658D01*
X190316Y281799D01*
X190429Y281912D01*
X190527Y282010D01*
X190626Y282095D01*
X190711Y282166D01*
X190767Y282208D01*
X190809Y282236D01*
X190823Y282250D01*
X190612Y282335D01*
X190429Y282447D01*
X190273Y282574D01*
X190147Y282687D01*
X190034Y282800D01*
X189963Y282885D01*
X189921Y282941D01*
X189907Y282969D01*
X189794Y283166D01*
X189710Y283378D01*
X189653Y283589D01*
X189611Y283801D01*
X189583Y283970D01*
X189569Y284125D01*
Y284252D01*
X189583Y284506D01*
X189625Y284745D01*
X189667Y284957D01*
X189724Y285140D01*
X189794Y285295D01*
X189837Y285408D01*
X189879Y285478D01*
X189893Y285506D01*
X190020Y285704D01*
X190161Y285873D01*
X190302Y286028D01*
X190443Y286155D01*
X190555Y286254D01*
X190654Y286338D01*
X190711Y286381D01*
X190739Y286395D01*
X189724D01*
Y287466D01*
X196800D01*
Y286268D01*
D02*
G37*
G36*
X207139Y281390D02*
X207280Y281376D01*
X207576Y281306D01*
X207816Y281207D01*
X208027Y281094D01*
X208197Y280981D01*
X208323Y280883D01*
X208394Y280812D01*
X208422Y280784D01*
X208605Y280530D01*
X208746Y280248D01*
X208845Y279938D01*
X208915Y279656D01*
X208958Y279403D01*
X208972Y279290D01*
Y279191D01*
X208986Y279107D01*
Y278994D01*
X208972Y278740D01*
X208944Y278486D01*
X208915Y278261D01*
X208873Y278063D01*
X208831Y277908D01*
X208789Y277781D01*
X208774Y277697D01*
X208760Y277669D01*
X208662Y277429D01*
X208535Y277203D01*
X208394Y276992D01*
X208267Y276780D01*
X208140Y276611D01*
X208041Y276484D01*
X207971Y276400D01*
X207943Y276386D01*
Y276372D01*
X208126Y276343D01*
X208295Y276315D01*
X208450Y276287D01*
X208577Y276245D01*
X208690Y276203D01*
X208760Y276174D01*
X208817Y276160D01*
X208831Y276146D01*
Y274891D01*
X208676Y274962D01*
X208521Y275032D01*
X208380Y275089D01*
X208253Y275117D01*
X208140Y275159D01*
X208055Y275173D01*
X207999Y275187D01*
X207985D01*
X207886Y275202D01*
X207759Y275216D01*
X207619D01*
X207463Y275230D01*
X207111Y275244D01*
X206759D01*
X206420Y275258D01*
X206265D01*
X206138D01*
X206026D01*
X205941D01*
X205885D01*
X205870D01*
X204263D01*
X203996D01*
X203756Y275272D01*
X203573Y275286D01*
X203418D01*
X203305Y275300D01*
X203220Y275314D01*
X203178Y275329D01*
X203164D01*
X202981Y275371D01*
X202826Y275427D01*
X202699Y275483D01*
X202572Y275554D01*
X202487Y275610D01*
X202417Y275653D01*
X202374Y275681D01*
X202360Y275695D01*
X202248Y275808D01*
X202135Y275935D01*
X202050Y276076D01*
X201966Y276217D01*
X201909Y276343D01*
X201867Y276442D01*
X201839Y276513D01*
X201825Y276541D01*
X201754Y276766D01*
X201698Y277006D01*
X201656Y277246D01*
X201627Y277485D01*
X201613Y277697D01*
X201599Y277852D01*
Y278007D01*
X201613Y278345D01*
X201641Y278641D01*
X201684Y278923D01*
X201726Y279149D01*
X201768Y279346D01*
X201810Y279487D01*
X201825Y279543D01*
X201839Y279586D01*
X201853Y279600D01*
Y279614D01*
X201952Y279854D01*
X202078Y280065D01*
X202191Y280248D01*
X202304Y280403D01*
X202417Y280516D01*
X202501Y280601D01*
X202558Y280657D01*
X202572Y280671D01*
X202755Y280798D01*
X202952Y280911D01*
X203150Y280996D01*
X203333Y281066D01*
X203516Y281122D01*
X203643Y281165D01*
X203699Y281179D01*
X203742D01*
X203756Y281193D01*
X203770D01*
X203925Y280023D01*
X203671Y279938D01*
X203446Y279854D01*
X203263Y279755D01*
X203121Y279670D01*
X203009Y279586D01*
X202938Y279515D01*
X202896Y279459D01*
X202882Y279445D01*
X202783Y279276D01*
X202713Y279078D01*
X202656Y278867D01*
X202628Y278669D01*
X202600Y278472D01*
X202586Y278331D01*
Y278190D01*
X202600Y277866D01*
X202642Y277584D01*
X202713Y277358D01*
X202783Y277161D01*
X202868Y277020D01*
X202924Y276907D01*
X202981Y276837D01*
X202995Y276823D01*
X203121Y276710D01*
X203277Y276625D01*
X203446Y276555D01*
X203615Y276513D01*
X203770Y276484D01*
X203911Y276470D01*
X203996D01*
X204010D01*
X204024D01*
X204052D01*
X204108D01*
X204207D01*
X204292Y276484D01*
X204320D01*
X204334D01*
X204376Y276625D01*
X204419Y276780D01*
X204503Y277105D01*
X204573Y277471D01*
X204644Y277810D01*
X204672Y277979D01*
X204686Y278134D01*
X204715Y278275D01*
X204729Y278388D01*
X204743Y278486D01*
Y278557D01*
X204757Y278613D01*
Y278627D01*
X204785Y278881D01*
X204827Y279092D01*
X204855Y279276D01*
X204884Y279417D01*
X204898Y279529D01*
X204926Y279614D01*
X204940Y279670D01*
Y279685D01*
X204996Y279868D01*
X205053Y280023D01*
X205123Y280178D01*
X205180Y280305D01*
X205236Y280417D01*
X205292Y280488D01*
X205321Y280544D01*
X205335Y280558D01*
X205433Y280699D01*
X205546Y280812D01*
X205659Y280925D01*
X205772Y281010D01*
X205870Y281080D01*
X205955Y281136D01*
X206011Y281165D01*
X206026Y281179D01*
X206181Y281249D01*
X206350Y281306D01*
X206505Y281348D01*
X206660Y281376D01*
X206787Y281390D01*
X206885Y281404D01*
X206942D01*
X206970D01*
X207139Y281390D01*
D02*
G37*
G36*
X195109Y276484D02*
X195250Y276470D01*
X195546Y276400D01*
X195786Y276301D01*
X195997Y276188D01*
X196166Y276076D01*
X196293Y275977D01*
X196363Y275907D01*
X196392Y275878D01*
X196575Y275625D01*
X196716Y275343D01*
X196814Y275032D01*
X196885Y274750D01*
X196927Y274497D01*
X196941Y274384D01*
Y274285D01*
X196956Y274201D01*
Y274088D01*
X196941Y273834D01*
X196913Y273580D01*
X196885Y273355D01*
X196843Y273158D01*
X196800Y273002D01*
X196758Y272876D01*
X196744Y272791D01*
X196730Y272763D01*
X196631Y272523D01*
X196504Y272298D01*
X196363Y272086D01*
X196237Y271875D01*
X196110Y271706D01*
X196011Y271579D01*
X195940Y271494D01*
X195912Y271480D01*
Y271466D01*
X196096Y271438D01*
X196265Y271409D01*
X196420Y271381D01*
X196547Y271339D01*
X196660Y271297D01*
X196730Y271269D01*
X196786Y271254D01*
X196800Y271240D01*
Y269986D01*
X196645Y270056D01*
X196490Y270127D01*
X196349Y270183D01*
X196222Y270211D01*
X196110Y270254D01*
X196025Y270268D01*
X195969Y270282D01*
X195955D01*
X195856Y270296D01*
X195729Y270310D01*
X195588D01*
X195433Y270324D01*
X195081Y270338D01*
X194728D01*
X194390Y270352D01*
X194235D01*
X194108D01*
X193995D01*
X193911D01*
X193854D01*
X193840D01*
X192233D01*
X191965D01*
X191726Y270366D01*
X191542Y270380D01*
X191387D01*
X191274Y270394D01*
X191190Y270409D01*
X191147Y270423D01*
X191133D01*
X190950Y270465D01*
X190795Y270521D01*
X190668Y270578D01*
X190541Y270648D01*
X190457Y270705D01*
X190386Y270747D01*
X190344Y270775D01*
X190330Y270789D01*
X190217Y270902D01*
X190104Y271029D01*
X190020Y271170D01*
X189935Y271311D01*
X189879Y271438D01*
X189837Y271536D01*
X189808Y271607D01*
X189794Y271635D01*
X189724Y271861D01*
X189667Y272100D01*
X189625Y272340D01*
X189597Y272580D01*
X189583Y272791D01*
X189569Y272946D01*
Y273101D01*
X189583Y273440D01*
X189611Y273736D01*
X189653Y274018D01*
X189696Y274243D01*
X189738Y274440D01*
X189780Y274581D01*
X189794Y274638D01*
X189808Y274680D01*
X189822Y274694D01*
Y274708D01*
X189921Y274948D01*
X190048Y275159D01*
X190161Y275343D01*
X190273Y275498D01*
X190386Y275610D01*
X190471Y275695D01*
X190527Y275751D01*
X190541Y275765D01*
X190725Y275892D01*
X190922Y276005D01*
X191119Y276090D01*
X191303Y276160D01*
X191486Y276217D01*
X191613Y276259D01*
X191669Y276273D01*
X191711D01*
X191726Y276287D01*
X191740D01*
X191895Y275117D01*
X191641Y275032D01*
X191415Y274948D01*
X191232Y274849D01*
X191091Y274765D01*
X190978Y274680D01*
X190908Y274610D01*
X190866Y274553D01*
X190851Y274539D01*
X190753Y274370D01*
X190682Y274172D01*
X190626Y273961D01*
X190598Y273764D01*
X190570Y273566D01*
X190555Y273425D01*
Y273284D01*
X190570Y272960D01*
X190612Y272678D01*
X190682Y272453D01*
X190753Y272255D01*
X190837Y272114D01*
X190894Y272002D01*
X190950Y271931D01*
X190964Y271917D01*
X191091Y271804D01*
X191246Y271720D01*
X191415Y271649D01*
X191585Y271607D01*
X191740Y271579D01*
X191881Y271565D01*
X191965D01*
X191979D01*
X191993D01*
X192022D01*
X192078D01*
X192177D01*
X192261Y271579D01*
X192289D01*
X192304D01*
X192346Y271720D01*
X192388Y271875D01*
X192473Y272199D01*
X192543Y272565D01*
X192614Y272904D01*
X192642Y273073D01*
X192656Y273228D01*
X192684Y273369D01*
X192698Y273482D01*
X192712Y273580D01*
Y273651D01*
X192726Y273707D01*
Y273721D01*
X192755Y273975D01*
X192797Y274187D01*
X192825Y274370D01*
X192853Y274511D01*
X192867Y274624D01*
X192896Y274708D01*
X192910Y274765D01*
Y274779D01*
X192966Y274962D01*
X193022Y275117D01*
X193093Y275272D01*
X193149Y275399D01*
X193206Y275512D01*
X193262Y275582D01*
X193290Y275639D01*
X193304Y275653D01*
X193403Y275794D01*
X193516Y275907D01*
X193629Y276019D01*
X193741Y276104D01*
X193840Y276174D01*
X193925Y276231D01*
X193981Y276259D01*
X193995Y276273D01*
X194150Y276343D01*
X194319Y276400D01*
X194474Y276442D01*
X194629Y276470D01*
X194756Y276484D01*
X194855Y276499D01*
X194911D01*
X194940D01*
X195109Y276484D01*
D02*
G37*
G36*
X208831Y272213D02*
X204982D01*
X204743D01*
X204503Y272185D01*
X204306Y272157D01*
X204122Y272129D01*
X203953Y272086D01*
X203798Y272044D01*
X203657Y271987D01*
X203544Y271931D01*
X203446Y271889D01*
X203361Y271832D01*
X203291Y271790D01*
X203234Y271748D01*
X203164Y271691D01*
X203136Y271663D01*
X202966Y271452D01*
X202854Y271226D01*
X202769Y271001D01*
X202699Y270803D01*
X202670Y270620D01*
X202656Y270479D01*
X202642Y270423D01*
Y270352D01*
X202656Y270183D01*
X202670Y270014D01*
X202713Y269873D01*
X202755Y269760D01*
X202797Y269662D01*
X202826Y269577D01*
X202854Y269535D01*
X202868Y269520D01*
X202952Y269394D01*
X203051Y269281D01*
X203150Y269196D01*
X203234Y269126D01*
X203319Y269083D01*
X203389Y269041D01*
X203432Y269013D01*
X203446D01*
X203601Y268971D01*
X203770Y268928D01*
X203953Y268900D01*
X204137Y268886D01*
X204292Y268872D01*
X204419D01*
X204517D01*
X204531D01*
X204545D01*
X208831D01*
Y267674D01*
X204489D01*
X204193D01*
X203953Y267688D01*
X203756Y267702D01*
X203587D01*
X203474Y267716D01*
X203389Y267730D01*
X203333Y267744D01*
X203319D01*
X203136Y267787D01*
X202966Y267857D01*
X202826Y267913D01*
X202684Y267970D01*
X202586Y268040D01*
X202515Y268083D01*
X202459Y268111D01*
X202445Y268125D01*
X202304Y268238D01*
X202191Y268365D01*
X202078Y268491D01*
X201994Y268632D01*
X201923Y268745D01*
X201881Y268844D01*
X201853Y268900D01*
X201839Y268928D01*
X201754Y269126D01*
X201698Y269337D01*
X201656Y269535D01*
X201627Y269718D01*
X201613Y269873D01*
X201599Y269986D01*
Y270098D01*
X201613Y270366D01*
X201656Y270620D01*
X201712Y270846D01*
X201782Y271071D01*
X201867Y271269D01*
X201966Y271452D01*
X202078Y271621D01*
X202177Y271762D01*
X202290Y271903D01*
X202403Y272016D01*
X202501Y272114D01*
X202586Y272199D01*
X202656Y272255D01*
X202713Y272298D01*
X202755Y272326D01*
X202769Y272340D01*
X201754D01*
Y273411D01*
X208831D01*
Y272213D01*
D02*
G37*
G36*
X196800Y267307D02*
X192952D01*
X192712D01*
X192473Y267279D01*
X192275Y267251D01*
X192092Y267223D01*
X191923Y267180D01*
X191768Y267138D01*
X191627Y267082D01*
X191514Y267025D01*
X191415Y266983D01*
X191331Y266927D01*
X191260Y266884D01*
X191204Y266842D01*
X191133Y266786D01*
X191105Y266758D01*
X190936Y266546D01*
X190823Y266320D01*
X190739Y266095D01*
X190668Y265898D01*
X190640Y265714D01*
X190626Y265573D01*
X190612Y265517D01*
Y265446D01*
X190626Y265277D01*
X190640Y265108D01*
X190682Y264967D01*
X190725Y264854D01*
X190767Y264756D01*
X190795Y264671D01*
X190823Y264629D01*
X190837Y264615D01*
X190922Y264488D01*
X191021Y264375D01*
X191119Y264291D01*
X191204Y264220D01*
X191289Y264178D01*
X191359Y264135D01*
X191401Y264107D01*
X191415D01*
X191570Y264065D01*
X191740Y264023D01*
X191923Y263995D01*
X192106Y263980D01*
X192261Y263966D01*
X192388D01*
X192487D01*
X192501D01*
X192515D01*
X196800D01*
Y262768D01*
X192459D01*
X192162D01*
X191923Y262782D01*
X191726Y262796D01*
X191556D01*
X191444Y262810D01*
X191359Y262824D01*
X191303Y262838D01*
X191289D01*
X191105Y262881D01*
X190936Y262951D01*
X190795Y263008D01*
X190654Y263064D01*
X190555Y263135D01*
X190485Y263177D01*
X190429Y263205D01*
X190415Y263219D01*
X190273Y263332D01*
X190161Y263459D01*
X190048Y263586D01*
X189963Y263727D01*
X189893Y263839D01*
X189851Y263938D01*
X189822Y263995D01*
X189808Y264023D01*
X189724Y264220D01*
X189667Y264431D01*
X189625Y264629D01*
X189597Y264812D01*
X189583Y264967D01*
X189569Y265080D01*
Y265193D01*
X189583Y265461D01*
X189625Y265714D01*
X189681Y265940D01*
X189752Y266165D01*
X189837Y266363D01*
X189935Y266546D01*
X190048Y266715D01*
X190147Y266856D01*
X190259Y266997D01*
X190372Y267110D01*
X190471Y267209D01*
X190555Y267293D01*
X190626Y267350D01*
X190682Y267392D01*
X190725Y267420D01*
X190739Y267434D01*
X189724D01*
Y268505D01*
X196800D01*
Y267307D01*
D02*
G37*
G36*
X206054Y262289D02*
X206392Y262232D01*
X206688Y262148D01*
X206956Y262049D01*
X207167Y261950D01*
X207252Y261908D01*
X207322Y261880D01*
X207379Y261838D01*
X207421Y261824D01*
X207449Y261795D01*
X207463D01*
X207731Y261584D01*
X207971Y261358D01*
X208168Y261119D01*
X208337Y260893D01*
X208464Y260696D01*
X208549Y260527D01*
X208577Y260470D01*
X208605Y260428D01*
X208619Y260400D01*
Y260386D01*
X208746Y260033D01*
X208845Y259667D01*
X208901Y259300D01*
X208958Y258948D01*
X208972Y258779D01*
X208986Y258638D01*
Y258511D01*
X209000Y258398D01*
Y258172D01*
X208986Y257792D01*
X208944Y257439D01*
X208873Y257115D01*
X208803Y256847D01*
X208746Y256622D01*
X208704Y256523D01*
X208676Y256439D01*
X208648Y256382D01*
X208633Y256340D01*
X208619Y256312D01*
Y256297D01*
X208464Y256001D01*
X208295Y255748D01*
X208112Y255522D01*
X207943Y255339D01*
X207802Y255198D01*
X207675Y255099D01*
X207590Y255029D01*
X207576Y255015D01*
X207562D01*
X207294Y254860D01*
X207041Y254747D01*
X206801Y254676D01*
X206575Y254620D01*
X206378Y254592D01*
X206223Y254564D01*
X206166D01*
X206124D01*
X206110D01*
X206096D01*
X205814Y254578D01*
X205546Y254620D01*
X205307Y254690D01*
X205109Y254761D01*
X204940Y254846D01*
X204813Y254902D01*
X204743Y254958D01*
X204715Y254972D01*
X204503Y255142D01*
X204306Y255339D01*
X204137Y255550D01*
X203981Y255762D01*
X203869Y255945D01*
X203784Y256100D01*
X203756Y256157D01*
X203728Y256199D01*
X203714Y256227D01*
Y256241D01*
X203657Y256354D01*
X203615Y256495D01*
X203559Y256650D01*
X203502Y256819D01*
X203403Y257171D01*
X203305Y257538D01*
X203263Y257707D01*
X203220Y257862D01*
X203178Y258017D01*
X203150Y258144D01*
X203121Y258243D01*
X203107Y258328D01*
X203093Y258384D01*
Y258398D01*
X203023Y258680D01*
X202966Y258934D01*
X202896Y259159D01*
X202840Y259357D01*
X202769Y259540D01*
X202713Y259695D01*
X202656Y259836D01*
X202614Y259963D01*
X202558Y260061D01*
X202515Y260146D01*
X202487Y260202D01*
X202445Y260259D01*
X202403Y260329D01*
X202388Y260343D01*
X202248Y260470D01*
X202107Y260555D01*
X201966Y260625D01*
X201825Y260668D01*
X201712Y260696D01*
X201613Y260710D01*
X201557D01*
X201529D01*
X201303Y260682D01*
X201106Y260625D01*
X200937Y260541D01*
X200781Y260442D01*
X200669Y260357D01*
X200570Y260273D01*
X200514Y260217D01*
X200499Y260188D01*
X200429Y260075D01*
X200359Y259963D01*
X200246Y259695D01*
X200175Y259413D01*
X200119Y259131D01*
X200091Y258877D01*
X200077Y258764D01*
X200063Y258680D01*
Y258483D01*
X200077Y258088D01*
X200133Y257735D01*
X200218Y257453D01*
X200302Y257214D01*
X200387Y257031D01*
X200471Y256890D01*
X200528Y256819D01*
X200542Y256791D01*
X200739Y256594D01*
X200951Y256439D01*
X201176Y256312D01*
X201402Y256227D01*
X201613Y256171D01*
X201768Y256128D01*
X201839Y256114D01*
X201881Y256100D01*
X201909D01*
X201923D01*
X201825Y254860D01*
X201514Y254888D01*
X201232Y254958D01*
X200965Y255029D01*
X200739Y255128D01*
X200556Y255212D01*
X200415Y255282D01*
X200373Y255311D01*
X200330Y255339D01*
X200316Y255353D01*
X200302D01*
X200063Y255536D01*
X199851Y255734D01*
X199668Y255945D01*
X199527Y256157D01*
X199400Y256340D01*
X199329Y256481D01*
X199301Y256537D01*
X199273Y256579D01*
X199259Y256608D01*
Y256622D01*
X199146Y256932D01*
X199062Y257270D01*
X198991Y257580D01*
X198949Y257876D01*
X198921Y258144D01*
Y258243D01*
X198906Y258342D01*
Y258525D01*
X198921Y258891D01*
X198963Y259216D01*
X199019Y259526D01*
X199076Y259794D01*
X199132Y260005D01*
X199160Y260104D01*
X199188Y260174D01*
X199217Y260231D01*
X199231Y260273D01*
X199245Y260301D01*
Y260315D01*
X199386Y260597D01*
X199541Y260851D01*
X199710Y261062D01*
X199865Y261231D01*
X200006Y261358D01*
X200119Y261457D01*
X200203Y261528D01*
X200218Y261542D01*
X200232D01*
X200471Y261683D01*
X200711Y261781D01*
X200951Y261852D01*
X201162Y261894D01*
X201345Y261922D01*
X201486Y261950D01*
X201543D01*
X201585D01*
X201599D01*
X201613D01*
X201853Y261936D01*
X202078Y261894D01*
X202290Y261838D01*
X202473Y261781D01*
X202614Y261725D01*
X202727Y261668D01*
X202797Y261626D01*
X202826Y261612D01*
X203023Y261471D01*
X203206Y261302D01*
X203361Y261133D01*
X203488Y260964D01*
X203601Y260823D01*
X203671Y260696D01*
X203728Y260611D01*
X203742Y260597D01*
Y260583D01*
X203798Y260470D01*
X203855Y260343D01*
X203953Y260061D01*
X204052Y259737D01*
X204151Y259427D01*
X204235Y259145D01*
X204263Y259018D01*
X204292Y258906D01*
X204320Y258821D01*
X204334Y258750D01*
X204348Y258708D01*
Y258694D01*
X204404Y258454D01*
X204461Y258229D01*
X204517Y258032D01*
X204559Y257862D01*
X204602Y257693D01*
X204644Y257552D01*
X204672Y257425D01*
X204715Y257327D01*
X204743Y257228D01*
X204757Y257157D01*
X204799Y257045D01*
X204813Y256974D01*
X204827Y256960D01*
X204912Y256749D01*
X205011Y256565D01*
X205109Y256410D01*
X205194Y256297D01*
X205278Y256199D01*
X205335Y256143D01*
X205377Y256100D01*
X205391Y256086D01*
X205518Y255987D01*
X205659Y255917D01*
X205800Y255875D01*
X205913Y255832D01*
X206026Y255818D01*
X206110Y255804D01*
X206181D01*
X206195D01*
X206364Y255818D01*
X206519Y255846D01*
X206660Y255889D01*
X206773Y255945D01*
X206885Y256001D01*
X206956Y256044D01*
X207012Y256072D01*
X207026Y256086D01*
X207167Y256199D01*
X207280Y256340D01*
X207379Y256481D01*
X207477Y256608D01*
X207534Y256735D01*
X207590Y256833D01*
X207619Y256904D01*
X207633Y256932D01*
X207703Y257143D01*
X207759Y257369D01*
X207788Y257595D01*
X207816Y257792D01*
X207830Y257961D01*
X207844Y258102D01*
Y258229D01*
X207830Y258539D01*
X207802Y258821D01*
X207759Y259075D01*
X207703Y259300D01*
X207647Y259484D01*
X207604Y259624D01*
X207590Y259667D01*
X207576Y259709D01*
X207562Y259723D01*
Y259737D01*
X207449Y259963D01*
X207322Y260174D01*
X207196Y260329D01*
X207069Y260470D01*
X206970Y260583D01*
X206871Y260653D01*
X206815Y260696D01*
X206801Y260710D01*
X206618Y260809D01*
X206420Y260907D01*
X206209Y260964D01*
X206026Y261020D01*
X205842Y261062D01*
X205715Y261091D01*
X205659D01*
X205617Y261105D01*
X205603D01*
X205588D01*
X205701Y262317D01*
X206054Y262289D01*
D02*
G37*
G36*
X193671Y261358D02*
X194037Y261316D01*
X194362Y261246D01*
X194644Y261175D01*
X194771Y261147D01*
X194869Y261119D01*
X194968Y261076D01*
X195052Y261048D01*
X195109Y261020D01*
X195151Y261006D01*
X195179Y260992D01*
X195193D01*
X195489Y260837D01*
X195743Y260653D01*
X195969Y260470D01*
X196152Y260287D01*
X196293Y260132D01*
X196406Y260005D01*
X196462Y259921D01*
X196490Y259906D01*
Y259892D01*
X196645Y259624D01*
X196758Y259357D01*
X196843Y259089D01*
X196899Y258849D01*
X196927Y258652D01*
X196941Y258483D01*
X196956Y258426D01*
Y258342D01*
X196941Y258102D01*
X196913Y257876D01*
X196857Y257665D01*
X196786Y257482D01*
X196716Y257298D01*
X196631Y257129D01*
X196533Y256988D01*
X196434Y256861D01*
X196335Y256735D01*
X196237Y256636D01*
X196152Y256551D01*
X196082Y256481D01*
X196011Y256424D01*
X195955Y256382D01*
X195926Y256368D01*
X195912Y256354D01*
X196800D01*
Y255240D01*
X187045D01*
Y256439D01*
X190541D01*
X190386Y256565D01*
X190259Y256706D01*
X190133Y256833D01*
X190034Y256974D01*
X189963Y257087D01*
X189893Y257171D01*
X189865Y257228D01*
X189851Y257256D01*
X189752Y257439D01*
X189681Y257637D01*
X189639Y257834D01*
X189597Y258017D01*
X189583Y258172D01*
X189569Y258285D01*
Y258398D01*
X189583Y258708D01*
X189639Y259004D01*
X189710Y259272D01*
X189794Y259498D01*
X189893Y259695D01*
X189963Y259836D01*
X189992Y259892D01*
X190020Y259935D01*
X190034Y259949D01*
Y259963D01*
X190217Y260217D01*
X190443Y260428D01*
X190654Y260611D01*
X190866Y260752D01*
X191063Y260865D01*
X191218Y260949D01*
X191274Y260978D01*
X191317Y261006D01*
X191345Y261020D01*
X191359D01*
X191683Y261133D01*
X192022Y261217D01*
X192346Y261288D01*
X192642Y261330D01*
X192896Y261358D01*
X193008D01*
X193093Y261373D01*
X193178D01*
X193234D01*
X193262D01*
X193276D01*
X193671Y261358D01*
D02*
G37*
G36*
X202684Y252745D02*
X206773D01*
X206970D01*
X207139D01*
X207294Y252731D01*
X207449Y252717D01*
X207576D01*
X207689Y252703D01*
X207872Y252675D01*
X208013Y252646D01*
X208112Y252632D01*
X208168Y252604D01*
X208182D01*
X208309Y252548D01*
X208408Y252463D01*
X208507Y252379D01*
X208577Y252308D01*
X208648Y252223D01*
X208690Y252167D01*
X208718Y252125D01*
X208732Y252111D01*
X208803Y251956D01*
X208845Y251801D01*
X208887Y251631D01*
X208901Y251462D01*
X208915Y251321D01*
X208930Y251208D01*
Y251096D01*
X208915Y250786D01*
X208901Y250630D01*
X208873Y250490D01*
X208859Y250363D01*
X208845Y250264D01*
X208831Y250208D01*
Y250179D01*
X207773Y250334D01*
X207788Y250447D01*
X207802Y250560D01*
Y250659D01*
X207816Y250729D01*
Y250870D01*
X207802Y251053D01*
X207773Y251180D01*
X207745Y251251D01*
X207731Y251279D01*
X207661Y251378D01*
X207590Y251434D01*
X207534Y251476D01*
X207506Y251490D01*
X207435Y251505D01*
X207337Y251519D01*
X207111Y251533D01*
X207012Y251547D01*
X206928D01*
X206871D01*
X206843D01*
X202684D01*
Y250334D01*
X201754D01*
Y251547D01*
X199287D01*
X200006Y252745D01*
X201754D01*
Y253633D01*
X202684D01*
Y252745D01*
D02*
G37*
G36*
X208831Y247445D02*
X207463D01*
Y248812D01*
X208831D01*
Y247445D01*
D02*
G37*
G36*
X193586Y253774D02*
X193897Y253746D01*
X194178Y253704D01*
X194446Y253647D01*
X194686Y253577D01*
X194911Y253506D01*
X195123Y253422D01*
X195306Y253337D01*
X195475Y253253D01*
X195616Y253168D01*
X195729Y253097D01*
X195828Y253027D01*
X195912Y252971D01*
X195969Y252928D01*
X195997Y252900D01*
X196011Y252886D01*
X196180Y252703D01*
X196321Y252519D01*
X196448Y252322D01*
X196561Y252125D01*
X196645Y251928D01*
X196730Y251716D01*
X196843Y251335D01*
X196871Y251166D01*
X196899Y250997D01*
X196927Y250856D01*
X196941Y250729D01*
X196956Y250616D01*
Y250476D01*
X196941Y250137D01*
X196885Y249827D01*
X196814Y249531D01*
X196744Y249291D01*
X196660Y249080D01*
X196631Y248995D01*
X196603Y248925D01*
X196575Y248854D01*
X196547Y248812D01*
X196533Y248798D01*
Y248784D01*
X196349Y248502D01*
X196152Y248262D01*
X195955Y248051D01*
X195757Y247882D01*
X195588Y247755D01*
X195447Y247656D01*
X195391Y247628D01*
X195348Y247600D01*
X195334Y247586D01*
X195320D01*
X194996Y247445D01*
X194644Y247346D01*
X194291Y247261D01*
X193939Y247219D01*
X193784Y247191D01*
X193643D01*
X193502Y247177D01*
X193389Y247163D01*
X193290D01*
X193220D01*
X193178D01*
X193163D01*
X192853Y247177D01*
X192571Y247205D01*
X192304Y247247D01*
X192050Y247304D01*
X191810Y247374D01*
X191599Y247459D01*
X191387Y247543D01*
X191218Y247628D01*
X191063Y247712D01*
X190922Y247797D01*
X190795Y247882D01*
X190696Y247952D01*
X190626Y248008D01*
X190570Y248051D01*
X190541Y248079D01*
X190527Y248093D01*
X190358Y248276D01*
X190217Y248460D01*
X190076Y248657D01*
X189977Y248854D01*
X189879Y249052D01*
X189808Y249249D01*
X189681Y249630D01*
X189653Y249813D01*
X189625Y249968D01*
X189597Y250109D01*
X189583Y250236D01*
X189569Y250334D01*
Y250476D01*
X189583Y250715D01*
X189597Y250941D01*
X189696Y251378D01*
X189822Y251758D01*
X189893Y251928D01*
X189963Y252083D01*
X190034Y252223D01*
X190104Y252336D01*
X190175Y252449D01*
X190231Y252534D01*
X190288Y252604D01*
X190330Y252661D01*
X190344Y252689D01*
X190358Y252703D01*
X190541Y252900D01*
X190753Y253055D01*
X190978Y253210D01*
X191204Y253323D01*
X191444Y253436D01*
X191697Y253520D01*
X191937Y253591D01*
X192162Y253647D01*
X192388Y253704D01*
X192585Y253732D01*
X192783Y253760D01*
X192938Y253774D01*
X193079D01*
X193178Y253788D01*
X193234D01*
X193262D01*
X193586Y253774D01*
D02*
G37*
G36*
X206589Y242060D02*
X206829Y242017D01*
X207041Y241989D01*
X207238Y241933D01*
X207407Y241876D01*
X207576Y241820D01*
X207717Y241763D01*
X207844Y241693D01*
X207957Y241637D01*
X208055Y241580D01*
X208126Y241524D01*
X208182Y241482D01*
X208239Y241453D01*
X208253Y241439D01*
X208267Y241425D01*
X208394Y241284D01*
X208507Y241143D01*
X208605Y240988D01*
X208690Y240819D01*
X208817Y240495D01*
X208901Y240185D01*
X208958Y239889D01*
X208972Y239776D01*
X208986Y239663D01*
X209000Y239578D01*
Y239452D01*
X208986Y239142D01*
X208944Y238860D01*
X208887Y238606D01*
X208817Y238380D01*
X208760Y238197D01*
X208704Y238070D01*
X208662Y237985D01*
X208648Y237957D01*
X208507Y237732D01*
X208337Y237534D01*
X208168Y237379D01*
X208013Y237238D01*
X207858Y237140D01*
X207745Y237069D01*
X207661Y237027D01*
X207647Y237013D01*
X207633D01*
X207351Y236914D01*
X207055Y236830D01*
X206730Y236773D01*
X206420Y236745D01*
X206152Y236717D01*
X206040D01*
X205927Y236703D01*
X205842D01*
X205786D01*
X205744D01*
X205730D01*
X199076D01*
Y238000D01*
X205800D01*
X206096D01*
X206350Y238028D01*
X206561Y238042D01*
X206730Y238070D01*
X206857Y238098D01*
X206956Y238112D01*
X207012Y238141D01*
X207026D01*
X207167Y238197D01*
X207280Y238267D01*
X207379Y238352D01*
X207477Y238423D01*
X207534Y238507D01*
X207590Y238563D01*
X207619Y238606D01*
X207633Y238620D01*
X207703Y238761D01*
X207759Y238902D01*
X207788Y239043D01*
X207816Y239170D01*
X207830Y239296D01*
X207844Y239381D01*
Y239466D01*
X207830Y239691D01*
X207773Y239903D01*
X207717Y240072D01*
X207633Y240227D01*
X207562Y240340D01*
X207492Y240424D01*
X207449Y240481D01*
X207435Y240495D01*
X207351Y240565D01*
X207252Y240622D01*
X207026Y240706D01*
X206773Y240791D01*
X206519Y240833D01*
X206279Y240875D01*
X206181D01*
X206096Y240889D01*
X206011Y240904D01*
X205955D01*
X205927D01*
X205913D01*
X206082Y242074D01*
X206350D01*
X206589Y242060D01*
D02*
G37*
G36*
X196800Y240509D02*
X192839D01*
Y238014D01*
X192825Y237647D01*
X192797Y237295D01*
X192755Y236985D01*
X192698Y236703D01*
X192642Y236435D01*
X192571Y236209D01*
X192487Y235998D01*
X192402Y235815D01*
X192332Y235660D01*
X192247Y235519D01*
X192177Y235406D01*
X192106Y235321D01*
X192064Y235251D01*
X192022Y235208D01*
X191993Y235180D01*
X191979Y235166D01*
X191810Y235025D01*
X191641Y234898D01*
X191472Y234800D01*
X191289Y234701D01*
X191105Y234616D01*
X190936Y234560D01*
X190612Y234461D01*
X190457Y234433D01*
X190316Y234405D01*
X190189Y234391D01*
X190090Y234377D01*
X189992Y234363D01*
X189935D01*
X189893D01*
X189879D01*
X189611Y234377D01*
X189357Y234405D01*
X189132Y234461D01*
X188934Y234504D01*
X188765Y234560D01*
X188638Y234616D01*
X188568Y234645D01*
X188540Y234659D01*
X188328Y234771D01*
X188145Y234912D01*
X187976Y235039D01*
X187849Y235166D01*
X187750Y235279D01*
X187666Y235364D01*
X187623Y235420D01*
X187609Y235448D01*
X187496Y235631D01*
X187398Y235843D01*
X187313Y236040D01*
X187243Y236223D01*
X187200Y236393D01*
X187172Y236519D01*
X187144Y236618D01*
Y236646D01*
X187116Y236858D01*
X187088Y237097D01*
X187073Y237351D01*
X187059Y237591D01*
X187045Y237802D01*
Y241806D01*
X196800D01*
Y240509D01*
D02*
G37*
G36*
Y231670D02*
X189724D01*
Y232868D01*
X196800D01*
Y231670D01*
D02*
G37*
G36*
X188413D02*
X187045D01*
Y232868D01*
X188413D01*
Y231670D01*
D02*
G37*
G36*
X207139Y235138D02*
X207280Y235124D01*
X207576Y235053D01*
X207816Y234955D01*
X208027Y234842D01*
X208197Y234729D01*
X208323Y234630D01*
X208394Y234560D01*
X208422Y234532D01*
X208605Y234278D01*
X208746Y233996D01*
X208845Y233686D01*
X208915Y233404D01*
X208958Y233150D01*
X208972Y233037D01*
Y232939D01*
X208986Y232854D01*
Y232741D01*
X208972Y232488D01*
X208944Y232234D01*
X208915Y232008D01*
X208873Y231811D01*
X208831Y231656D01*
X208789Y231529D01*
X208774Y231444D01*
X208760Y231416D01*
X208662Y231177D01*
X208535Y230951D01*
X208394Y230740D01*
X208267Y230528D01*
X208140Y230359D01*
X208041Y230232D01*
X207971Y230148D01*
X207943Y230133D01*
Y230119D01*
X208126Y230091D01*
X208295Y230063D01*
X208450Y230035D01*
X208577Y229993D01*
X208690Y229950D01*
X208760Y229922D01*
X208817Y229908D01*
X208831Y229894D01*
Y228639D01*
X208676Y228710D01*
X208521Y228780D01*
X208380Y228837D01*
X208253Y228865D01*
X208140Y228907D01*
X208055Y228921D01*
X207999Y228935D01*
X207985D01*
X207886Y228949D01*
X207759Y228963D01*
X207619D01*
X207463Y228978D01*
X207111Y228992D01*
X206759D01*
X206420Y229006D01*
X206265D01*
X206138D01*
X206026D01*
X205941D01*
X205885D01*
X205870D01*
X204263D01*
X203996D01*
X203756Y229020D01*
X203573Y229034D01*
X203418D01*
X203305Y229048D01*
X203220Y229062D01*
X203178Y229076D01*
X203164D01*
X202981Y229118D01*
X202826Y229175D01*
X202699Y229231D01*
X202572Y229302D01*
X202487Y229358D01*
X202417Y229401D01*
X202374Y229429D01*
X202360Y229443D01*
X202248Y229555D01*
X202135Y229682D01*
X202050Y229823D01*
X201966Y229964D01*
X201909Y230091D01*
X201867Y230190D01*
X201839Y230260D01*
X201825Y230289D01*
X201754Y230514D01*
X201698Y230754D01*
X201656Y230993D01*
X201627Y231233D01*
X201613Y231444D01*
X201599Y231600D01*
Y231755D01*
X201613Y232093D01*
X201641Y232389D01*
X201684Y232671D01*
X201726Y232896D01*
X201768Y233094D01*
X201810Y233235D01*
X201825Y233291D01*
X201839Y233333D01*
X201853Y233348D01*
Y233362D01*
X201952Y233601D01*
X202078Y233813D01*
X202191Y233996D01*
X202304Y234151D01*
X202417Y234264D01*
X202501Y234349D01*
X202558Y234405D01*
X202572Y234419D01*
X202755Y234546D01*
X202952Y234659D01*
X203150Y234743D01*
X203333Y234814D01*
X203516Y234870D01*
X203643Y234912D01*
X203699Y234926D01*
X203742D01*
X203756Y234941D01*
X203770D01*
X203925Y233771D01*
X203671Y233686D01*
X203446Y233601D01*
X203263Y233503D01*
X203121Y233418D01*
X203009Y233333D01*
X202938Y233263D01*
X202896Y233207D01*
X202882Y233193D01*
X202783Y233023D01*
X202713Y232826D01*
X202656Y232615D01*
X202628Y232417D01*
X202600Y232220D01*
X202586Y232079D01*
Y231938D01*
X202600Y231614D01*
X202642Y231332D01*
X202713Y231106D01*
X202783Y230909D01*
X202868Y230768D01*
X202924Y230655D01*
X202981Y230585D01*
X202995Y230571D01*
X203121Y230458D01*
X203277Y230373D01*
X203446Y230303D01*
X203615Y230260D01*
X203770Y230232D01*
X203911Y230218D01*
X203996D01*
X204010D01*
X204024D01*
X204052D01*
X204108D01*
X204207D01*
X204292Y230232D01*
X204320D01*
X204334D01*
X204376Y230373D01*
X204419Y230528D01*
X204503Y230852D01*
X204573Y231219D01*
X204644Y231557D01*
X204672Y231726D01*
X204686Y231882D01*
X204715Y232022D01*
X204729Y232135D01*
X204743Y232234D01*
Y232304D01*
X204757Y232361D01*
Y232375D01*
X204785Y232629D01*
X204827Y232840D01*
X204855Y233023D01*
X204884Y233164D01*
X204898Y233277D01*
X204926Y233362D01*
X204940Y233418D01*
Y233432D01*
X204996Y233615D01*
X205053Y233771D01*
X205123Y233926D01*
X205180Y234053D01*
X205236Y234165D01*
X205292Y234236D01*
X205321Y234292D01*
X205335Y234306D01*
X205433Y234447D01*
X205546Y234560D01*
X205659Y234673D01*
X205772Y234757D01*
X205870Y234828D01*
X205955Y234884D01*
X206011Y234912D01*
X206026Y234926D01*
X206181Y234997D01*
X206350Y235053D01*
X206505Y235096D01*
X206660Y235124D01*
X206787Y235138D01*
X206885Y235152D01*
X206942D01*
X206970D01*
X207139Y235138D01*
D02*
G37*
G36*
X196800Y228639D02*
X192952D01*
X192712D01*
X192473Y228611D01*
X192275Y228583D01*
X192092Y228555D01*
X191923Y228512D01*
X191768Y228470D01*
X191627Y228414D01*
X191514Y228357D01*
X191415Y228315D01*
X191331Y228259D01*
X191260Y228216D01*
X191204Y228174D01*
X191133Y228118D01*
X191105Y228089D01*
X190936Y227878D01*
X190823Y227652D01*
X190739Y227427D01*
X190668Y227229D01*
X190640Y227046D01*
X190626Y226905D01*
X190612Y226849D01*
Y226778D01*
X190626Y226609D01*
X190640Y226440D01*
X190682Y226299D01*
X190725Y226186D01*
X190767Y226088D01*
X190795Y226003D01*
X190823Y225961D01*
X190837Y225947D01*
X190922Y225820D01*
X191021Y225707D01*
X191119Y225623D01*
X191204Y225552D01*
X191289Y225510D01*
X191359Y225467D01*
X191401Y225439D01*
X191415D01*
X191570Y225397D01*
X191740Y225355D01*
X191923Y225326D01*
X192106Y225312D01*
X192261Y225298D01*
X192388D01*
X192487D01*
X192501D01*
X192515D01*
X196800D01*
Y224100D01*
X192459D01*
X192162D01*
X191923Y224114D01*
X191726Y224128D01*
X191556D01*
X191444Y224142D01*
X191359Y224156D01*
X191303Y224170D01*
X191289D01*
X191105Y224213D01*
X190936Y224283D01*
X190795Y224340D01*
X190654Y224396D01*
X190555Y224466D01*
X190485Y224509D01*
X190429Y224537D01*
X190415Y224551D01*
X190273Y224664D01*
X190161Y224791D01*
X190048Y224918D01*
X189963Y225059D01*
X189893Y225171D01*
X189851Y225270D01*
X189822Y225326D01*
X189808Y225355D01*
X189724Y225552D01*
X189667Y225763D01*
X189625Y225961D01*
X189597Y226144D01*
X189583Y226299D01*
X189569Y226412D01*
Y226525D01*
X189583Y226793D01*
X189625Y227046D01*
X189681Y227272D01*
X189752Y227497D01*
X189837Y227695D01*
X189935Y227878D01*
X190048Y228047D01*
X190147Y228188D01*
X190259Y228329D01*
X190372Y228442D01*
X190471Y228540D01*
X190555Y228625D01*
X190626Y228682D01*
X190682Y228724D01*
X190725Y228752D01*
X190739Y228766D01*
X189724D01*
Y229837D01*
X196800D01*
Y228639D01*
D02*
G37*
G36*
X195109Y222648D02*
X195250Y222634D01*
X195546Y222563D01*
X195786Y222465D01*
X195997Y222352D01*
X196166Y222239D01*
X196293Y222141D01*
X196363Y222070D01*
X196392Y222042D01*
X196575Y221788D01*
X196716Y221506D01*
X196814Y221196D01*
X196885Y220914D01*
X196927Y220660D01*
X196941Y220548D01*
Y220449D01*
X196956Y220364D01*
Y220252D01*
X196941Y219998D01*
X196913Y219744D01*
X196885Y219519D01*
X196843Y219321D01*
X196800Y219166D01*
X196758Y219039D01*
X196744Y218955D01*
X196730Y218926D01*
X196631Y218687D01*
X196504Y218461D01*
X196363Y218250D01*
X196237Y218038D01*
X196110Y217869D01*
X196011Y217742D01*
X195940Y217658D01*
X195912Y217644D01*
Y217630D01*
X196096Y217601D01*
X196265Y217573D01*
X196420Y217545D01*
X196547Y217503D01*
X196660Y217460D01*
X196730Y217432D01*
X196786Y217418D01*
X196800Y217404D01*
Y216149D01*
X196645Y216220D01*
X196490Y216290D01*
X196349Y216347D01*
X196222Y216375D01*
X196110Y216417D01*
X196025Y216431D01*
X195969Y216445D01*
X195955D01*
X195856Y216459D01*
X195729Y216474D01*
X195588D01*
X195433Y216488D01*
X195081Y216502D01*
X194728D01*
X194390Y216516D01*
X194235D01*
X194108D01*
X193995D01*
X193911D01*
X193854D01*
X193840D01*
X192233D01*
X191965D01*
X191726Y216530D01*
X191542Y216544D01*
X191387D01*
X191274Y216558D01*
X191190Y216572D01*
X191147Y216586D01*
X191133D01*
X190950Y216629D01*
X190795Y216685D01*
X190668Y216741D01*
X190541Y216812D01*
X190457Y216868D01*
X190386Y216910D01*
X190344Y216939D01*
X190330Y216953D01*
X190217Y217066D01*
X190104Y217192D01*
X190020Y217333D01*
X189935Y217474D01*
X189879Y217601D01*
X189837Y217700D01*
X189808Y217770D01*
X189794Y217799D01*
X189724Y218024D01*
X189667Y218264D01*
X189625Y218503D01*
X189597Y218743D01*
X189583Y218955D01*
X189569Y219110D01*
Y219265D01*
X189583Y219603D01*
X189611Y219899D01*
X189653Y220181D01*
X189696Y220407D01*
X189738Y220604D01*
X189780Y220745D01*
X189794Y220801D01*
X189808Y220844D01*
X189822Y220858D01*
Y220872D01*
X189921Y221111D01*
X190048Y221323D01*
X190161Y221506D01*
X190273Y221661D01*
X190386Y221774D01*
X190471Y221859D01*
X190527Y221915D01*
X190541Y221929D01*
X190725Y222056D01*
X190922Y222169D01*
X191119Y222253D01*
X191303Y222324D01*
X191486Y222380D01*
X191613Y222422D01*
X191669Y222437D01*
X191711D01*
X191726Y222451D01*
X191740D01*
X191895Y221281D01*
X191641Y221196D01*
X191415Y221111D01*
X191232Y221013D01*
X191091Y220928D01*
X190978Y220844D01*
X190908Y220773D01*
X190866Y220717D01*
X190851Y220703D01*
X190753Y220533D01*
X190682Y220336D01*
X190626Y220125D01*
X190598Y219927D01*
X190570Y219730D01*
X190555Y219589D01*
Y219448D01*
X190570Y219124D01*
X190612Y218842D01*
X190682Y218616D01*
X190753Y218419D01*
X190837Y218278D01*
X190894Y218165D01*
X190950Y218095D01*
X190964Y218081D01*
X191091Y217968D01*
X191246Y217883D01*
X191415Y217813D01*
X191585Y217770D01*
X191740Y217742D01*
X191881Y217728D01*
X191965D01*
X191979D01*
X191993D01*
X192022D01*
X192078D01*
X192177D01*
X192261Y217742D01*
X192289D01*
X192304D01*
X192346Y217883D01*
X192388Y218038D01*
X192473Y218363D01*
X192543Y218729D01*
X192614Y219067D01*
X192642Y219237D01*
X192656Y219392D01*
X192684Y219533D01*
X192698Y219645D01*
X192712Y219744D01*
Y219814D01*
X192726Y219871D01*
Y219885D01*
X192755Y220139D01*
X192797Y220350D01*
X192825Y220533D01*
X192853Y220674D01*
X192867Y220787D01*
X192896Y220872D01*
X192910Y220928D01*
Y220942D01*
X192966Y221126D01*
X193022Y221281D01*
X193093Y221436D01*
X193149Y221562D01*
X193206Y221675D01*
X193262Y221746D01*
X193290Y221802D01*
X193304Y221816D01*
X193403Y221957D01*
X193516Y222070D01*
X193629Y222183D01*
X193741Y222267D01*
X193840Y222338D01*
X193925Y222394D01*
X193981Y222422D01*
X193995Y222437D01*
X194150Y222507D01*
X194319Y222563D01*
X194474Y222606D01*
X194629Y222634D01*
X194756Y222648D01*
X194855Y222662D01*
X194911D01*
X194940D01*
X195109Y222648D01*
D02*
G37*
G36*
X208831Y225975D02*
X205166D01*
X204827Y225961D01*
X204531Y225947D01*
X204277Y225919D01*
X204066Y225876D01*
X203911Y225834D01*
X203798Y225806D01*
X203728Y225792D01*
X203699Y225777D01*
X203516Y225693D01*
X203361Y225594D01*
X203220Y225496D01*
X203107Y225397D01*
X203023Y225298D01*
X202966Y225228D01*
X202924Y225171D01*
X202910Y225157D01*
X202826Y224988D01*
X202755Y224833D01*
X202713Y224664D01*
X202670Y224523D01*
X202656Y224410D01*
X202642Y224311D01*
Y224227D01*
X202656Y223987D01*
X202699Y223790D01*
X202769Y223621D01*
X202840Y223494D01*
X202924Y223395D01*
X202981Y223325D01*
X203037Y223282D01*
X203051Y223268D01*
X203220Y223170D01*
X203403Y223099D01*
X203601Y223043D01*
X203798Y223015D01*
X203967Y222986D01*
X204122Y222972D01*
X204179D01*
X204207D01*
X204235D01*
X204249D01*
X208831D01*
Y221774D01*
X204729D01*
X204348Y221746D01*
X204024Y221689D01*
X203756Y221619D01*
X203530Y221520D01*
X203361Y221436D01*
X203248Y221351D01*
X203178Y221295D01*
X203150Y221281D01*
X202981Y221083D01*
X202854Y220872D01*
X202769Y220660D01*
X202699Y220463D01*
X202670Y220294D01*
X202656Y220153D01*
X202642Y220096D01*
Y220026D01*
X202656Y219871D01*
X202670Y219744D01*
X202699Y219617D01*
X202741Y219519D01*
X202783Y219420D01*
X202811Y219363D01*
X202826Y219321D01*
X202840Y219307D01*
X202924Y219194D01*
X203009Y219110D01*
X203093Y219039D01*
X203178Y218983D01*
X203248Y218941D01*
X203305Y218912D01*
X203347Y218884D01*
X203361D01*
X203488Y218842D01*
X203657Y218814D01*
X203826Y218799D01*
X203996Y218785D01*
X204151Y218771D01*
X204277D01*
X204362D01*
X204376D01*
X204390D01*
X208831D01*
Y217573D01*
X203981D01*
X203756D01*
X203559Y217601D01*
X203361Y217630D01*
X203192Y217658D01*
X203023Y217700D01*
X202882Y217756D01*
X202755Y217799D01*
X202628Y217855D01*
X202530Y217911D01*
X202431Y217954D01*
X202304Y218052D01*
X202219Y218109D01*
X202191Y218137D01*
X201994Y218363D01*
X201853Y218630D01*
X201740Y218898D01*
X201670Y219152D01*
X201627Y219392D01*
X201613Y219490D01*
Y219589D01*
X201599Y219659D01*
Y219758D01*
X201613Y220012D01*
X201656Y220237D01*
X201712Y220463D01*
X201796Y220674D01*
X201895Y220872D01*
X201994Y221055D01*
X202107Y221210D01*
X202219Y221365D01*
X202346Y221506D01*
X202459Y221619D01*
X202558Y221718D01*
X202656Y221802D01*
X202741Y221873D01*
X202797Y221915D01*
X202840Y221943D01*
X202854Y221957D01*
X202642Y222042D01*
X202459Y222155D01*
X202304Y222281D01*
X202177Y222394D01*
X202064Y222507D01*
X201994Y222592D01*
X201952Y222648D01*
X201937Y222676D01*
X201825Y222873D01*
X201740Y223085D01*
X201684Y223297D01*
X201641Y223508D01*
X201613Y223677D01*
X201599Y223832D01*
Y223959D01*
X201613Y224213D01*
X201656Y224452D01*
X201698Y224664D01*
X201754Y224847D01*
X201825Y225002D01*
X201867Y225115D01*
X201909Y225186D01*
X201923Y225214D01*
X202050Y225411D01*
X202191Y225580D01*
X202332Y225735D01*
X202473Y225862D01*
X202586Y225961D01*
X202684Y226045D01*
X202741Y226088D01*
X202769Y226102D01*
X201754D01*
Y227173D01*
X208831D01*
Y225975D01*
D02*
G37*
G36*
X196800Y213499D02*
X187045D01*
Y214697D01*
X196800D01*
Y213499D01*
D02*
G37*
G36*
X205673Y216192D02*
X205969Y216163D01*
X206251Y216121D01*
X206505Y216065D01*
X206744Y215994D01*
X206970Y215924D01*
X207167Y215839D01*
X207351Y215755D01*
X207506Y215670D01*
X207647Y215585D01*
X207759Y215515D01*
X207858Y215444D01*
X207943Y215388D01*
X207999Y215346D01*
X208027Y215318D01*
X208041Y215303D01*
X208211Y215120D01*
X208351Y214937D01*
X208478Y214740D01*
X208591Y214528D01*
X208676Y214331D01*
X208760Y214119D01*
X208873Y213725D01*
X208901Y213541D01*
X208930Y213372D01*
X208958Y213217D01*
X208972Y213090D01*
X208986Y212992D01*
Y212836D01*
X208958Y212400D01*
X208887Y212005D01*
X208803Y211652D01*
X208746Y211511D01*
X208690Y211370D01*
X208633Y211243D01*
X208577Y211131D01*
X208535Y211046D01*
X208493Y210962D01*
X208450Y210905D01*
X208422Y210863D01*
X208394Y210835D01*
Y210821D01*
X208140Y210539D01*
X207872Y210313D01*
X207590Y210116D01*
X207322Y209975D01*
X207083Y209862D01*
X206970Y209820D01*
X206885Y209777D01*
X206801Y209749D01*
X206744Y209735D01*
X206716Y209721D01*
X206702D01*
X206547Y210962D01*
X206815Y211074D01*
X207041Y211201D01*
X207238Y211328D01*
X207393Y211441D01*
X207506Y211540D01*
X207590Y211624D01*
X207647Y211695D01*
X207661Y211709D01*
X207773Y211892D01*
X207858Y212075D01*
X207915Y212273D01*
X207957Y212442D01*
X207985Y212597D01*
X207999Y212724D01*
Y212836D01*
X207985Y213006D01*
X207971Y213161D01*
X207900Y213443D01*
X207802Y213696D01*
X207689Y213922D01*
X207590Y214091D01*
X207492Y214218D01*
X207421Y214303D01*
X207393Y214317D01*
Y214331D01*
X207139Y214528D01*
X206857Y214683D01*
X206547Y214796D01*
X206265Y214881D01*
X206011Y214923D01*
X205899Y214951D01*
X205800Y214965D01*
X205715D01*
X205659Y214979D01*
X205617D01*
X205603D01*
Y209693D01*
X205462Y209679D01*
X205363D01*
X205307D01*
X205292D01*
X204968Y209693D01*
X204672Y209721D01*
X204390Y209763D01*
X204122Y209820D01*
X203883Y209890D01*
X203657Y209961D01*
X203460Y210045D01*
X203277Y210130D01*
X203107Y210214D01*
X202966Y210299D01*
X202854Y210369D01*
X202755Y210440D01*
X202670Y210496D01*
X202614Y210539D01*
X202586Y210567D01*
X202572Y210581D01*
X202403Y210750D01*
X202248Y210933D01*
X202121Y211131D01*
X202008Y211328D01*
X201909Y211525D01*
X201839Y211709D01*
X201768Y211906D01*
X201726Y212075D01*
X201684Y212258D01*
X201656Y212414D01*
X201627Y212554D01*
X201613Y212667D01*
X201599Y212766D01*
Y212907D01*
X201613Y213175D01*
X201641Y213429D01*
X201684Y213668D01*
X201754Y213894D01*
X201825Y214105D01*
X201909Y214303D01*
X201994Y214486D01*
X202092Y214641D01*
X202177Y214796D01*
X202276Y214923D01*
X202360Y215036D01*
X202431Y215120D01*
X202501Y215191D01*
X202544Y215247D01*
X202572Y215275D01*
X202586Y215289D01*
X202783Y215444D01*
X202995Y215585D01*
X203206Y215712D01*
X203432Y215825D01*
X203671Y215910D01*
X203897Y215980D01*
X204348Y216093D01*
X204545Y216135D01*
X204743Y216163D01*
X204912Y216178D01*
X205067Y216192D01*
X205194Y216206D01*
X205278D01*
X205349D01*
X205363D01*
X205673Y216192D01*
D02*
G37*
G36*
X193643Y212033D02*
X193939Y212005D01*
X194221Y211963D01*
X194474Y211906D01*
X194714Y211836D01*
X194940Y211765D01*
X195137Y211681D01*
X195320Y211596D01*
X195475Y211511D01*
X195616Y211427D01*
X195729Y211356D01*
X195828Y211286D01*
X195912Y211229D01*
X195969Y211187D01*
X195997Y211159D01*
X196011Y211145D01*
X196180Y210962D01*
X196321Y210778D01*
X196448Y210581D01*
X196561Y210369D01*
X196645Y210172D01*
X196730Y209961D01*
X196843Y209566D01*
X196871Y209383D01*
X196899Y209214D01*
X196927Y209058D01*
X196941Y208932D01*
X196956Y208833D01*
Y208678D01*
X196927Y208241D01*
X196857Y207846D01*
X196772Y207494D01*
X196716Y207353D01*
X196660Y207212D01*
X196603Y207085D01*
X196547Y206972D01*
X196504Y206887D01*
X196462Y206803D01*
X196420Y206747D01*
X196392Y206704D01*
X196363Y206676D01*
Y206662D01*
X196110Y206380D01*
X195842Y206154D01*
X195560Y205957D01*
X195292Y205816D01*
X195052Y205703D01*
X194940Y205661D01*
X194855Y205619D01*
X194771Y205591D01*
X194714Y205576D01*
X194686Y205562D01*
X194672D01*
X194517Y206803D01*
X194785Y206916D01*
X195010Y207043D01*
X195208Y207169D01*
X195363Y207282D01*
X195475Y207381D01*
X195560Y207465D01*
X195616Y207536D01*
X195630Y207550D01*
X195743Y207733D01*
X195828Y207917D01*
X195884Y208114D01*
X195926Y208283D01*
X195955Y208438D01*
X195969Y208565D01*
Y208678D01*
X195955Y208847D01*
X195940Y209002D01*
X195870Y209284D01*
X195771Y209538D01*
X195659Y209763D01*
X195560Y209932D01*
X195461Y210059D01*
X195391Y210144D01*
X195363Y210158D01*
Y210172D01*
X195109Y210369D01*
X194827Y210525D01*
X194517Y210637D01*
X194235Y210722D01*
X193981Y210764D01*
X193868Y210792D01*
X193770Y210807D01*
X193685D01*
X193629Y210821D01*
X193586D01*
X193572D01*
Y205534D01*
X193431Y205520D01*
X193333D01*
X193276D01*
X193262D01*
X192938Y205534D01*
X192642Y205562D01*
X192360Y205605D01*
X192092Y205661D01*
X191852Y205732D01*
X191627Y205802D01*
X191430Y205887D01*
X191246Y205971D01*
X191077Y206056D01*
X190936Y206140D01*
X190823Y206211D01*
X190725Y206281D01*
X190640Y206338D01*
X190584Y206380D01*
X190555Y206408D01*
X190541Y206422D01*
X190372Y206591D01*
X190217Y206775D01*
X190090Y206972D01*
X189977Y207169D01*
X189879Y207367D01*
X189808Y207550D01*
X189738Y207747D01*
X189696Y207917D01*
X189653Y208100D01*
X189625Y208255D01*
X189597Y208396D01*
X189583Y208509D01*
X189569Y208607D01*
Y208748D01*
X189583Y209016D01*
X189611Y209270D01*
X189653Y209510D01*
X189724Y209735D01*
X189794Y209947D01*
X189879Y210144D01*
X189963Y210327D01*
X190062Y210482D01*
X190147Y210637D01*
X190245Y210764D01*
X190330Y210877D01*
X190400Y210962D01*
X190471Y211032D01*
X190513Y211089D01*
X190541Y211117D01*
X190555Y211131D01*
X190753Y211286D01*
X190964Y211427D01*
X191176Y211554D01*
X191401Y211666D01*
X191641Y211751D01*
X191866Y211821D01*
X192318Y211934D01*
X192515Y211977D01*
X192712Y212005D01*
X192882Y212019D01*
X193036Y212033D01*
X193163Y212047D01*
X193248D01*
X193319D01*
X193333D01*
X193643Y212033D01*
D02*
G37*
G36*
X207111Y208593D02*
X207463Y208466D01*
X207745Y208311D01*
X207985Y208156D01*
X208182Y208015D01*
X208309Y207888D01*
X208394Y207804D01*
X208408Y207790D01*
X208422Y207776D01*
X208521Y207635D01*
X208605Y207480D01*
X208746Y207141D01*
X208845Y206789D01*
X208915Y206451D01*
X208944Y206296D01*
X208958Y206154D01*
X208972Y206014D01*
Y205901D01*
X208986Y205802D01*
Y205675D01*
X208972Y205365D01*
X208944Y205097D01*
X208901Y204844D01*
X208845Y204618D01*
X208789Y204435D01*
X208746Y204294D01*
X208718Y204209D01*
X208704Y204195D01*
Y204181D01*
X208577Y203941D01*
X208450Y203744D01*
X208309Y203575D01*
X208182Y203420D01*
X208070Y203307D01*
X207971Y203236D01*
X207915Y203180D01*
X207886Y203166D01*
X207689Y203053D01*
X207477Y202969D01*
X207294Y202898D01*
X207125Y202856D01*
X206970Y202828D01*
X206857Y202813D01*
X206787D01*
X206759D01*
X206533Y202828D01*
X206336Y202856D01*
X206166Y202912D01*
X206011Y202955D01*
X205885Y203011D01*
X205800Y203067D01*
X205744Y203095D01*
X205730Y203110D01*
X205588Y203222D01*
X205462Y203349D01*
X205349Y203476D01*
X205264Y203603D01*
X205194Y203730D01*
X205152Y203814D01*
X205123Y203871D01*
X205109Y203899D01*
X205067Y203998D01*
X205025Y204110D01*
X204926Y204378D01*
X204827Y204674D01*
X204743Y204970D01*
X204658Y205238D01*
X204630Y205365D01*
X204602Y205464D01*
X204573Y205548D01*
X204559Y205619D01*
X204545Y205661D01*
Y205675D01*
X204503Y205830D01*
X204461Y205971D01*
X204433Y206098D01*
X204390Y206211D01*
X204348Y206394D01*
X204306Y206535D01*
X204263Y206634D01*
X204249Y206690D01*
X204235Y206718D01*
Y206733D01*
X204179Y206845D01*
X204137Y206944D01*
X204080Y207029D01*
X204038Y207085D01*
X203996Y207141D01*
X203953Y207169D01*
X203939Y207184D01*
X203925Y207198D01*
X203784Y207282D01*
X203643Y207325D01*
X203587D01*
X203544Y207339D01*
X203516D01*
X203502D01*
X203375Y207325D01*
X203248Y207282D01*
X203136Y207226D01*
X203051Y207155D01*
X202966Y207099D01*
X202910Y207043D01*
X202882Y207000D01*
X202868Y206986D01*
X202769Y206831D01*
X202699Y206648D01*
X202656Y206451D01*
X202614Y206267D01*
X202600Y206084D01*
X202586Y205943D01*
Y205802D01*
X202600Y205562D01*
X202628Y205337D01*
X202684Y205154D01*
X202741Y205013D01*
X202797Y204886D01*
X202854Y204801D01*
X202882Y204745D01*
X202896Y204731D01*
X203023Y204590D01*
X203164Y204491D01*
X203305Y204407D01*
X203432Y204336D01*
X203559Y204294D01*
X203657Y204265D01*
X203714Y204251D01*
X203742D01*
X203587Y203081D01*
X203347Y203138D01*
X203136Y203194D01*
X202952Y203265D01*
X202783Y203335D01*
X202670Y203406D01*
X202572Y203462D01*
X202515Y203490D01*
X202501Y203504D01*
X202360Y203631D01*
X202233Y203772D01*
X202121Y203927D01*
X202022Y204082D01*
X201952Y204223D01*
X201895Y204336D01*
X201867Y204407D01*
X201853Y204421D01*
Y204435D01*
X201768Y204674D01*
X201712Y204928D01*
X201656Y205168D01*
X201627Y205393D01*
X201613Y205605D01*
X201599Y205760D01*
Y206098D01*
X201627Y206296D01*
X201641Y206465D01*
X201670Y206620D01*
X201698Y206747D01*
X201726Y206845D01*
X201740Y206902D01*
X201754Y206930D01*
X201810Y207099D01*
X201867Y207254D01*
X201923Y207381D01*
X201980Y207494D01*
X202022Y207578D01*
X202064Y207635D01*
X202078Y207677D01*
X202092Y207691D01*
X202191Y207832D01*
X202304Y207945D01*
X202431Y208043D01*
X202530Y208128D01*
X202628Y208199D01*
X202699Y208241D01*
X202755Y208269D01*
X202769Y208283D01*
X202924Y208354D01*
X203065Y208410D01*
X203220Y208438D01*
X203347Y208466D01*
X203474Y208480D01*
X203559Y208495D01*
X203615D01*
X203643D01*
X203841Y208480D01*
X204010Y208452D01*
X204179Y208410D01*
X204320Y208368D01*
X204433Y208325D01*
X204531Y208283D01*
X204588Y208255D01*
X204602Y208241D01*
X204757Y208128D01*
X204884Y208001D01*
X204996Y207874D01*
X205095Y207747D01*
X205166Y207635D01*
X205222Y207550D01*
X205250Y207494D01*
X205264Y207465D01*
X205307Y207367D01*
X205363Y207240D01*
X205462Y206958D01*
X205546Y206662D01*
X205645Y206352D01*
X205715Y206084D01*
X205758Y205957D01*
X205786Y205844D01*
X205814Y205760D01*
X205828Y205689D01*
X205842Y205647D01*
Y205633D01*
X205885Y205450D01*
X205927Y205295D01*
X205969Y205154D01*
X206011Y205027D01*
X206040Y204914D01*
X206082Y204815D01*
X206138Y204646D01*
X206181Y204533D01*
X206223Y204463D01*
X206237Y204421D01*
X206251Y204407D01*
X206336Y204280D01*
X206448Y204195D01*
X206547Y204125D01*
X206646Y204082D01*
X206744Y204054D01*
X206815Y204040D01*
X206871D01*
X206885D01*
X207055Y204054D01*
X207196Y204096D01*
X207337Y204167D01*
X207449Y204237D01*
X207548Y204322D01*
X207619Y204378D01*
X207661Y204435D01*
X207675Y204449D01*
X207788Y204618D01*
X207858Y204801D01*
X207915Y205013D01*
X207957Y205210D01*
X207985Y205393D01*
X207999Y205534D01*
Y205675D01*
X207985Y205971D01*
X207943Y206225D01*
X207886Y206436D01*
X207816Y206620D01*
X207745Y206761D01*
X207689Y206873D01*
X207647Y206930D01*
X207633Y206958D01*
X207477Y207113D01*
X207294Y207240D01*
X207111Y207325D01*
X206942Y207395D01*
X206787Y207451D01*
X206646Y207480D01*
X206561Y207508D01*
X206547D01*
X206533D01*
X206716Y208692D01*
X207111Y208593D01*
D02*
G37*
G36*
X195081Y204435D02*
X195433Y204308D01*
X195715Y204153D01*
X195955Y203998D01*
X196152Y203857D01*
X196279Y203730D01*
X196363Y203645D01*
X196378Y203631D01*
X196392Y203617D01*
X196490Y203476D01*
X196575Y203321D01*
X196716Y202983D01*
X196814Y202630D01*
X196885Y202292D01*
X196913Y202137D01*
X196927Y201996D01*
X196941Y201855D01*
Y201742D01*
X196956Y201644D01*
Y201517D01*
X196941Y201206D01*
X196913Y200939D01*
X196871Y200685D01*
X196814Y200459D01*
X196758Y200276D01*
X196716Y200135D01*
X196688Y200051D01*
X196674Y200036D01*
Y200022D01*
X196547Y199783D01*
X196420Y199585D01*
X196279Y199416D01*
X196152Y199261D01*
X196039Y199148D01*
X195940Y199078D01*
X195884Y199021D01*
X195856Y199007D01*
X195659Y198895D01*
X195447Y198810D01*
X195264Y198739D01*
X195095Y198697D01*
X194940Y198669D01*
X194827Y198655D01*
X194756D01*
X194728D01*
X194503Y198669D01*
X194305Y198697D01*
X194136Y198754D01*
X193981Y198796D01*
X193854Y198852D01*
X193770Y198909D01*
X193713Y198937D01*
X193699Y198951D01*
X193558Y199064D01*
X193431Y199191D01*
X193319Y199317D01*
X193234Y199444D01*
X193163Y199571D01*
X193121Y199656D01*
X193093Y199712D01*
X193079Y199740D01*
X193036Y199839D01*
X192994Y199952D01*
X192896Y200220D01*
X192797Y200516D01*
X192712Y200812D01*
X192628Y201080D01*
X192600Y201206D01*
X192571Y201305D01*
X192543Y201390D01*
X192529Y201460D01*
X192515Y201502D01*
Y201517D01*
X192473Y201672D01*
X192430Y201813D01*
X192402Y201940D01*
X192360Y202052D01*
X192318Y202236D01*
X192275Y202376D01*
X192233Y202475D01*
X192219Y202532D01*
X192205Y202560D01*
Y202574D01*
X192148Y202687D01*
X192106Y202785D01*
X192050Y202870D01*
X192008Y202926D01*
X191965Y202983D01*
X191923Y203011D01*
X191909Y203025D01*
X191895Y203039D01*
X191754Y203124D01*
X191613Y203166D01*
X191556D01*
X191514Y203180D01*
X191486D01*
X191472D01*
X191345Y203166D01*
X191218Y203124D01*
X191105Y203067D01*
X191021Y202997D01*
X190936Y202940D01*
X190880Y202884D01*
X190851Y202842D01*
X190837Y202828D01*
X190739Y202673D01*
X190668Y202489D01*
X190626Y202292D01*
X190584Y202109D01*
X190570Y201925D01*
X190555Y201784D01*
Y201644D01*
X190570Y201404D01*
X190598Y201178D01*
X190654Y200995D01*
X190711Y200854D01*
X190767Y200727D01*
X190823Y200643D01*
X190851Y200586D01*
X190866Y200572D01*
X190993Y200431D01*
X191133Y200332D01*
X191274Y200248D01*
X191401Y200177D01*
X191528Y200135D01*
X191627Y200107D01*
X191683Y200093D01*
X191711D01*
X191556Y198923D01*
X191317Y198979D01*
X191105Y199035D01*
X190922Y199106D01*
X190753Y199177D01*
X190640Y199247D01*
X190541Y199303D01*
X190485Y199332D01*
X190471Y199346D01*
X190330Y199473D01*
X190203Y199613D01*
X190090Y199769D01*
X189992Y199924D01*
X189921Y200065D01*
X189865Y200177D01*
X189837Y200248D01*
X189822Y200262D01*
Y200276D01*
X189738Y200516D01*
X189681Y200769D01*
X189625Y201009D01*
X189597Y201235D01*
X189583Y201446D01*
X189569Y201601D01*
Y201940D01*
X189597Y202137D01*
X189611Y202306D01*
X189639Y202461D01*
X189667Y202588D01*
X189696Y202687D01*
X189710Y202743D01*
X189724Y202771D01*
X189780Y202940D01*
X189837Y203095D01*
X189893Y203222D01*
X189949Y203335D01*
X189992Y203420D01*
X190034Y203476D01*
X190048Y203518D01*
X190062Y203533D01*
X190161Y203673D01*
X190273Y203786D01*
X190400Y203885D01*
X190499Y203969D01*
X190598Y204040D01*
X190668Y204082D01*
X190725Y204110D01*
X190739Y204125D01*
X190894Y204195D01*
X191035Y204251D01*
X191190Y204280D01*
X191317Y204308D01*
X191444Y204322D01*
X191528Y204336D01*
X191585D01*
X191613D01*
X191810Y204322D01*
X191979Y204294D01*
X192148Y204251D01*
X192289Y204209D01*
X192402Y204167D01*
X192501Y204125D01*
X192557Y204096D01*
X192571Y204082D01*
X192726Y203969D01*
X192853Y203843D01*
X192966Y203716D01*
X193065Y203589D01*
X193135Y203476D01*
X193192Y203391D01*
X193220Y203335D01*
X193234Y203307D01*
X193276Y203208D01*
X193333Y203081D01*
X193431Y202799D01*
X193516Y202503D01*
X193615Y202193D01*
X193685Y201925D01*
X193727Y201798D01*
X193755Y201686D01*
X193784Y201601D01*
X193798Y201531D01*
X193812Y201488D01*
Y201474D01*
X193854Y201291D01*
X193897Y201136D01*
X193939Y200995D01*
X193981Y200868D01*
X194009Y200755D01*
X194051Y200657D01*
X194108Y200487D01*
X194150Y200375D01*
X194193Y200304D01*
X194207Y200262D01*
X194221Y200248D01*
X194305Y200121D01*
X194418Y200036D01*
X194517Y199966D01*
X194615Y199924D01*
X194714Y199895D01*
X194785Y199881D01*
X194841D01*
X194855D01*
X195024Y199895D01*
X195165Y199938D01*
X195306Y200008D01*
X195419Y200079D01*
X195518Y200163D01*
X195588Y200220D01*
X195630Y200276D01*
X195644Y200290D01*
X195757Y200459D01*
X195828Y200643D01*
X195884Y200854D01*
X195926Y201051D01*
X195955Y201235D01*
X195969Y201376D01*
Y201517D01*
X195955Y201813D01*
X195912Y202066D01*
X195856Y202278D01*
X195786Y202461D01*
X195715Y202602D01*
X195659Y202715D01*
X195616Y202771D01*
X195602Y202799D01*
X195447Y202955D01*
X195264Y203081D01*
X195081Y203166D01*
X194911Y203236D01*
X194756Y203293D01*
X194615Y203321D01*
X194531Y203349D01*
X194517D01*
X194503D01*
X194686Y204533D01*
X195081Y204435D01*
D02*
G37*
%LPC*%
G36*
X60598Y316487D02*
X54281D01*
Y316350D01*
X54007D01*
Y316213D01*
X53869D01*
Y315801D01*
X53732D01*
Y294654D01*
X53869D01*
Y294517D01*
X53732D01*
Y294242D01*
X53869D01*
Y293967D01*
X54007D01*
Y293830D01*
X54144D01*
Y293693D01*
X54556D01*
Y293555D01*
X60323D01*
Y293693D01*
X60735D01*
Y293830D01*
X60872D01*
Y293967D01*
X61010D01*
Y294379D01*
X61147D01*
Y300970D01*
X61284D01*
Y301108D01*
X61422D01*
Y301245D01*
X82980D01*
Y301383D01*
X83392D01*
Y301520D01*
X83530D01*
Y301657D01*
X83667D01*
Y308386D01*
X83530D01*
Y308523D01*
X83392D01*
Y308660D01*
X83255D01*
Y308798D01*
X61696D01*
Y308935D01*
X61422D01*
Y309072D01*
X61284D01*
Y309210D01*
X61147D01*
Y315801D01*
X61010D01*
Y316075D01*
X60872D01*
Y316213D01*
X60735D01*
Y316350D01*
X60598D01*
Y316487D01*
D02*
G37*
G36*
X83118Y291908D02*
X54418D01*
Y291770D01*
X54144D01*
Y291633D01*
X53869D01*
Y291221D01*
X53732D01*
Y284904D01*
X53869D01*
Y284630D01*
X54007D01*
Y284492D01*
X54144D01*
Y284355D01*
X83392D01*
Y284492D01*
X83530D01*
Y284630D01*
X83667D01*
Y291496D01*
X83530D01*
Y291633D01*
X83392D01*
Y291770D01*
X83118D01*
Y291908D01*
D02*
G37*
G36*
X111131Y291084D02*
X91220D01*
Y290946D01*
X90670D01*
Y290809D01*
X90396D01*
Y290672D01*
X90258D01*
Y290534D01*
X90121D01*
Y290397D01*
X89984D01*
Y290260D01*
X89846D01*
Y290122D01*
X89709D01*
Y289985D01*
X89572D01*
Y289848D01*
X89434D01*
Y289711D01*
X89297D01*
Y289573D01*
X89160D01*
Y289436D01*
X89022D01*
Y289298D01*
X88885D01*
Y289161D01*
X88748D01*
Y289024D01*
X88610D01*
Y288887D01*
X88473D01*
Y288749D01*
X88336D01*
Y288612D01*
X88198D01*
Y288475D01*
X88061D01*
Y288337D01*
X87924D01*
Y288200D01*
X87787D01*
Y288063D01*
X87649D01*
Y287925D01*
X87512D01*
Y287788D01*
X87375D01*
Y287651D01*
X87237D01*
Y287513D01*
X87100D01*
Y287376D01*
X86963D01*
Y287239D01*
X86825D01*
Y287101D01*
X86688D01*
Y286964D01*
X86551D01*
Y286689D01*
X86413D01*
Y286278D01*
X86276D01*
Y285866D01*
X86139D01*
Y269387D01*
X86276D01*
Y269250D01*
X86139D01*
Y268976D01*
X86276D01*
Y268564D01*
X86413D01*
Y268426D01*
X86551D01*
Y268289D01*
X93142D01*
Y268426D01*
X93279D01*
Y268564D01*
X93417D01*
Y268976D01*
X93554D01*
Y269525D01*
X93417D01*
Y269662D01*
X93554D01*
Y283257D01*
X93691D01*
Y283394D01*
X93828D01*
Y283531D01*
X108384D01*
Y283394D01*
X108659D01*
Y283119D01*
X108796D01*
Y268838D01*
X108933D01*
Y268564D01*
X109071D01*
Y268426D01*
X109208D01*
Y268289D01*
X115662D01*
Y268426D01*
X115799D01*
Y268564D01*
X115937D01*
Y268701D01*
X116074D01*
Y286140D01*
X115937D01*
Y286552D01*
X115799D01*
Y286827D01*
X115662D01*
Y286964D01*
X115525D01*
Y287101D01*
X115387D01*
Y287239D01*
X115250D01*
Y287376D01*
X115113D01*
Y287513D01*
X114975D01*
Y287651D01*
X114838D01*
Y287788D01*
X114701D01*
Y287925D01*
X114564D01*
Y288063D01*
X114426D01*
Y288200D01*
X114289D01*
Y288337D01*
X114151D01*
Y288475D01*
X114014D01*
Y288612D01*
X113877D01*
Y288749D01*
X113740D01*
Y288887D01*
X113602D01*
Y289024D01*
X113465D01*
Y289161D01*
X113328D01*
Y289298D01*
X113190D01*
Y289436D01*
X113053D01*
Y289573D01*
X112916D01*
Y289711D01*
X112778D01*
Y289848D01*
X112641D01*
Y289985D01*
X112504D01*
Y290122D01*
X112366D01*
Y290260D01*
X112229D01*
Y290397D01*
X112092D01*
Y290534D01*
X111954D01*
Y290672D01*
X111817D01*
Y290809D01*
X111543D01*
Y290946D01*
X111131D01*
Y291084D01*
D02*
G37*
G36*
X83255Y280922D02*
X54281D01*
Y280785D01*
X54007D01*
Y280648D01*
X53869D01*
Y280236D01*
X53732D01*
Y259226D01*
X61147D01*
Y259638D01*
X61010D01*
Y259775D01*
X61147D01*
Y261698D01*
X83255D01*
Y261835D01*
X83392D01*
Y261972D01*
X83530D01*
Y262110D01*
X83667D01*
Y268152D01*
X83530D01*
Y268426D01*
X83392D01*
Y268564D01*
X83118D01*
Y268701D01*
X61147D01*
Y273370D01*
X83118D01*
Y273507D01*
X83392D01*
Y273644D01*
X83530D01*
Y273782D01*
X83667D01*
Y280510D01*
X83530D01*
Y280785D01*
X83255D01*
Y280922D01*
D02*
G37*
G36*
X103715Y271585D02*
X97536D01*
Y271447D01*
X97261D01*
Y271310D01*
X96987D01*
Y271173D01*
X96849D01*
Y271035D01*
X96575D01*
Y270898D01*
X96438D01*
Y270761D01*
X96300D01*
Y270623D01*
X96163D01*
Y270486D01*
X96026D01*
Y270349D01*
X95888D01*
Y270211D01*
X95751D01*
Y270074D01*
X95614D01*
Y269937D01*
X95476D01*
Y269799D01*
X95339D01*
Y269662D01*
X95202D01*
Y269525D01*
X95064D01*
Y269387D01*
X94927D01*
Y269250D01*
X94790D01*
Y269113D01*
X94652D01*
Y268976D01*
X94515D01*
Y268838D01*
X94378D01*
Y268564D01*
X94241D01*
Y268426D01*
X94103D01*
Y268289D01*
X93966D01*
Y268152D01*
X93828D01*
Y268014D01*
X93691D01*
Y267877D01*
X93554D01*
Y267740D01*
X93417D01*
Y267602D01*
X93279D01*
Y267465D01*
X93142D01*
Y267328D01*
X93005D01*
Y267190D01*
X92867D01*
Y267053D01*
X92730D01*
Y266916D01*
X92593D01*
Y266779D01*
X92455D01*
Y266641D01*
X92318D01*
Y266504D01*
X92181D01*
Y266367D01*
X92043D01*
Y266229D01*
X91906D01*
Y266092D01*
X91769D01*
Y265955D01*
X91631D01*
Y265817D01*
X91494D01*
Y265680D01*
X91357D01*
Y265543D01*
X91220D01*
Y265405D01*
X91082D01*
Y265268D01*
X90945D01*
Y265131D01*
X90808D01*
Y264993D01*
X90670D01*
Y264856D01*
X90533D01*
Y264719D01*
X90396D01*
Y264581D01*
X90258D01*
Y264444D01*
X90121D01*
Y264307D01*
X89984D01*
Y264169D01*
X89846D01*
Y264032D01*
X89709D01*
Y263895D01*
X89572D01*
Y263757D01*
X89434D01*
Y263620D01*
X89297D01*
Y263483D01*
X89160D01*
Y263346D01*
X89022D01*
Y263208D01*
X88885D01*
Y263071D01*
X88748D01*
Y262934D01*
X88610D01*
Y262796D01*
X88473D01*
Y262659D01*
X88336D01*
Y262522D01*
X88198D01*
Y262384D01*
X88061D01*
Y262247D01*
X87924D01*
Y262110D01*
X87787D01*
Y261972D01*
X87649D01*
Y261835D01*
X87512D01*
Y261698D01*
X87375D01*
Y261560D01*
X87237D01*
Y261423D01*
X87100D01*
Y261286D01*
X86963D01*
Y261148D01*
X86825D01*
Y261011D01*
X86688D01*
Y260874D01*
X86551D01*
Y260737D01*
X86413D01*
Y260599D01*
X86276D01*
Y260462D01*
X86139D01*
Y260324D01*
X86001D01*
Y260187D01*
X85864D01*
Y260050D01*
X85727D01*
Y259913D01*
X85590D01*
Y259775D01*
X85452D01*
Y259638D01*
X85315D01*
Y259501D01*
X85177D01*
Y259226D01*
X85040D01*
Y259089D01*
X84903D01*
Y258951D01*
X84766D01*
Y258814D01*
X84628D01*
Y258677D01*
X84491D01*
Y258539D01*
X84354D01*
Y258402D01*
X84216D01*
Y258265D01*
X84079D01*
Y258127D01*
X83942D01*
Y257990D01*
X83804D01*
Y257853D01*
X83667D01*
Y257715D01*
X83530D01*
Y257578D01*
X83392D01*
Y257441D01*
X83255D01*
Y257304D01*
X83118D01*
Y257166D01*
X82980D01*
Y257029D01*
X82843D01*
Y256892D01*
X37391D01*
Y254420D01*
X37528D01*
Y253871D01*
X37666D01*
Y253596D01*
X37803D01*
Y253459D01*
X37940D01*
Y253321D01*
X38078D01*
Y253184D01*
X38215D01*
Y253047D01*
X38352D01*
Y252909D01*
X38490D01*
Y252772D01*
X38627D01*
Y252635D01*
X38764D01*
Y252497D01*
X38902D01*
Y252360D01*
X39039D01*
Y252223D01*
X39176D01*
Y252085D01*
X39313D01*
Y251948D01*
X39451D01*
Y251811D01*
X39588D01*
Y251674D01*
X39725D01*
Y251536D01*
X39863D01*
Y251399D01*
X40000D01*
Y251262D01*
X40137D01*
Y251124D01*
X40275D01*
Y250987D01*
X40412D01*
Y250850D01*
X40549D01*
Y250712D01*
X40687D01*
Y250575D01*
X40824D01*
Y250438D01*
X40961D01*
Y250300D01*
X41099D01*
Y250163D01*
X41236D01*
Y250026D01*
X41373D01*
Y249888D01*
X41511D01*
Y249751D01*
X41785D01*
Y249614D01*
X42334D01*
Y249477D01*
X85040D01*
Y249614D01*
X85590D01*
Y249751D01*
X85864D01*
Y249888D01*
X86139D01*
Y250026D01*
X86413D01*
Y250163D01*
X86551D01*
Y250300D01*
X86825D01*
Y250438D01*
X86963D01*
Y250575D01*
X87100D01*
Y250712D01*
X87237D01*
Y250850D01*
X87375D01*
Y250987D01*
X87512D01*
Y251124D01*
X87649D01*
Y251262D01*
X87787D01*
Y251399D01*
X87924D01*
Y251536D01*
X88061D01*
Y251674D01*
X88198D01*
Y251811D01*
X88336D01*
Y251948D01*
X88473D01*
Y252085D01*
X88610D01*
Y252223D01*
X88748D01*
Y252360D01*
X88885D01*
Y252497D01*
X89022D01*
Y252635D01*
X89160D01*
Y252772D01*
X89297D01*
Y252909D01*
X89434D01*
Y253047D01*
X89572D01*
Y253184D01*
X89709D01*
Y253321D01*
X89846D01*
Y253459D01*
X89984D01*
Y253596D01*
X90121D01*
Y253733D01*
X90258D01*
Y253871D01*
X90396D01*
Y254008D01*
X90533D01*
Y254145D01*
X90670D01*
Y254283D01*
X90808D01*
Y254420D01*
X90945D01*
Y254694D01*
X91082D01*
Y254832D01*
X91220D01*
Y254969D01*
X91357D01*
Y255107D01*
X91494D01*
Y255244D01*
X91631D01*
Y255381D01*
X91769D01*
Y255518D01*
X91906D01*
Y255656D01*
X92043D01*
Y255793D01*
X92181D01*
Y255930D01*
X92318D01*
Y256068D01*
X92455D01*
Y256205D01*
X92593D01*
Y256342D01*
X92730D01*
Y256480D01*
X92867D01*
Y256617D01*
X93005D01*
Y256754D01*
X93142D01*
Y256892D01*
X93279D01*
Y257029D01*
X93417D01*
Y257166D01*
X93554D01*
Y257304D01*
X93691D01*
Y257441D01*
X93828D01*
Y257578D01*
X93966D01*
Y257715D01*
X94103D01*
Y257853D01*
X94241D01*
Y257990D01*
X94378D01*
Y258127D01*
X94515D01*
Y258265D01*
X94652D01*
Y258402D01*
X94790D01*
Y258539D01*
X94927D01*
Y258677D01*
X95064D01*
Y258814D01*
X95202D01*
Y258951D01*
X95339D01*
Y259089D01*
X95476D01*
Y259226D01*
X95614D01*
Y259363D01*
X95751D01*
Y259501D01*
X95888D01*
Y259638D01*
X96026D01*
Y259775D01*
X96163D01*
Y259913D01*
X96300D01*
Y260050D01*
X96438D01*
Y260187D01*
X96575D01*
Y260324D01*
X96712D01*
Y260462D01*
X96849D01*
Y260599D01*
X96987D01*
Y260737D01*
X97124D01*
Y260874D01*
X97261D01*
Y261011D01*
X97399D01*
Y261148D01*
X97536D01*
Y261286D01*
X97673D01*
Y261423D01*
X97811D01*
Y261560D01*
X97948D01*
Y261698D01*
X98085D01*
Y261835D01*
X98223D01*
Y261972D01*
X98360D01*
Y262110D01*
X98497D01*
Y262247D01*
X98635D01*
Y262384D01*
X98772D01*
Y262522D01*
X98909D01*
Y262659D01*
X99047D01*
Y262796D01*
X99184D01*
Y262934D01*
X99321D01*
Y263071D01*
X99459D01*
Y263208D01*
X99596D01*
Y263346D01*
X99733D01*
Y263483D01*
X99871D01*
Y263620D01*
X100008D01*
Y263757D01*
X100145D01*
Y263895D01*
X100282D01*
Y264032D01*
X100420D01*
Y264169D01*
X100557D01*
Y264307D01*
X100694D01*
Y264444D01*
X100832D01*
Y264581D01*
X100969D01*
Y264719D01*
X101106D01*
Y264856D01*
X101244D01*
Y264993D01*
X101381D01*
Y265131D01*
X101518D01*
Y265268D01*
X101656D01*
Y265405D01*
X101793D01*
Y265543D01*
X101930D01*
Y265680D01*
X102068D01*
Y265817D01*
X102205D01*
Y265955D01*
X102342D01*
Y266092D01*
X102480D01*
Y266367D01*
X102617D01*
Y266504D01*
X102754D01*
Y266641D01*
X102892D01*
Y266779D01*
X103029D01*
Y266916D01*
X103166D01*
Y267053D01*
X103303D01*
Y267190D01*
X103441D01*
Y267328D01*
X103578D01*
Y267465D01*
X103715D01*
Y267602D01*
X103853D01*
Y267740D01*
X103990D01*
Y267877D01*
X104127D01*
Y268014D01*
X104265D01*
Y268152D01*
X104402D01*
Y268289D01*
X104539D01*
Y268426D01*
X104677D01*
Y268564D01*
X104814D01*
Y268701D01*
X104951D01*
Y268838D01*
X105089D01*
Y268976D01*
X105226D01*
Y269113D01*
X105363D01*
Y269250D01*
X105500D01*
Y269387D01*
X105638D01*
Y269525D01*
X105775D01*
Y269799D01*
X105638D01*
Y269937D01*
X105500D01*
Y270074D01*
X105363D01*
Y270211D01*
X105226D01*
Y270349D01*
X105089D01*
Y270486D01*
X104951D01*
Y270623D01*
X104814D01*
Y270761D01*
X104677D01*
Y270898D01*
X104539D01*
Y271035D01*
X104265D01*
Y271173D01*
X104127D01*
Y271310D01*
X103853D01*
Y271447D01*
X103715D01*
Y271585D01*
D02*
G37*
G36*
X115662Y264856D02*
X104677D01*
Y264719D01*
X104539D01*
Y264581D01*
X104402D01*
Y264444D01*
X104265D01*
Y264307D01*
X104127D01*
Y264169D01*
X103990D01*
Y264032D01*
X103853D01*
Y263757D01*
X103715D01*
Y263620D01*
X103578D01*
Y263483D01*
X103441D01*
Y263346D01*
X103303D01*
Y263208D01*
X103166D01*
Y263071D01*
X103029D01*
Y262934D01*
X102892D01*
Y262796D01*
X102754D01*
Y262659D01*
X102617D01*
Y262522D01*
X102480D01*
Y262384D01*
X102342D01*
Y262247D01*
X102205D01*
Y262110D01*
X102068D01*
Y261972D01*
X101930D01*
Y261835D01*
X101793D01*
Y261698D01*
X101656D01*
Y261560D01*
X101518D01*
Y261423D01*
X101381D01*
Y261286D01*
X101244D01*
Y261148D01*
X101106D01*
Y261011D01*
X100969D01*
Y260874D01*
X100832D01*
Y260737D01*
X100694D01*
Y260599D01*
X100557D01*
Y260462D01*
X100420D01*
Y260324D01*
X100282D01*
Y260187D01*
X100145D01*
Y260050D01*
X100008D01*
Y259913D01*
X99871D01*
Y259775D01*
X99733D01*
Y259638D01*
X99596D01*
Y259501D01*
X99459D01*
Y259363D01*
X99321D01*
Y259226D01*
X99184D01*
Y259089D01*
X99047D01*
Y258951D01*
X98909D01*
Y258814D01*
X98772D01*
Y258677D01*
X98635D01*
Y258539D01*
X98497D01*
Y258402D01*
X98360D01*
Y258265D01*
X98223D01*
Y258127D01*
X98085D01*
Y257990D01*
X97948D01*
Y257853D01*
X97811D01*
Y257715D01*
X97673D01*
Y257578D01*
X97536D01*
Y257441D01*
X97399D01*
Y257304D01*
X100420D01*
Y247279D01*
X92867D01*
Y253459D01*
X92730D01*
Y253321D01*
X92593D01*
Y253184D01*
X92455D01*
Y253047D01*
X92318D01*
Y252909D01*
X92181D01*
Y252772D01*
X92043D01*
Y252635D01*
X91906D01*
Y252497D01*
X91769D01*
Y252360D01*
X91631D01*
Y252223D01*
X91494D01*
Y252085D01*
X91357D01*
Y251948D01*
X91220D01*
Y251811D01*
X91082D01*
Y251674D01*
X90945D01*
Y251536D01*
X90808D01*
Y251399D01*
X90670D01*
Y251262D01*
X90533D01*
Y251124D01*
X90396D01*
Y250987D01*
X90258D01*
Y250850D01*
X90121D01*
Y250712D01*
X89984D01*
Y250575D01*
X89846D01*
Y250438D01*
X89709D01*
Y250300D01*
X89572D01*
Y250163D01*
X89434D01*
Y250026D01*
X89297D01*
Y249888D01*
X89160D01*
Y249751D01*
X89022D01*
Y249614D01*
X88885D01*
Y249477D01*
X88748D01*
Y249339D01*
X88610D01*
Y249202D01*
X88473D01*
Y249065D01*
X88336D01*
Y248927D01*
X88198D01*
Y248790D01*
X88061D01*
Y248653D01*
X87924D01*
Y248515D01*
X87787D01*
Y248378D01*
X87649D01*
Y248241D01*
X87512D01*
Y248103D01*
X87375D01*
Y247966D01*
X87237D01*
Y247829D01*
X87100D01*
Y247691D01*
X86963D01*
Y247554D01*
X86825D01*
Y247417D01*
X86688D01*
Y247279D01*
X86551D01*
Y247142D01*
X86413D01*
Y247005D01*
X86276D01*
Y246867D01*
X86139D01*
Y244945D01*
X86276D01*
Y244396D01*
X86413D01*
Y244121D01*
X86551D01*
Y243846D01*
X86688D01*
Y243709D01*
X86825D01*
Y243572D01*
X86963D01*
Y243435D01*
X87100D01*
Y243297D01*
X87237D01*
Y243160D01*
X87375D01*
Y243022D01*
X87512D01*
Y242885D01*
X87649D01*
Y242748D01*
X87787D01*
Y242611D01*
X87924D01*
Y242473D01*
X88061D01*
Y242336D01*
X88198D01*
Y242199D01*
X88336D01*
Y242061D01*
X88473D01*
Y241924D01*
X88610D01*
Y241787D01*
X88748D01*
Y241649D01*
X88885D01*
Y241512D01*
X89022D01*
Y241375D01*
X89160D01*
Y241237D01*
X89297D01*
Y241100D01*
X89434D01*
Y240963D01*
X89572D01*
Y240826D01*
X89709D01*
Y240688D01*
X89846D01*
Y240551D01*
X89984D01*
Y240413D01*
X90121D01*
Y240276D01*
X90258D01*
Y240139D01*
X90396D01*
Y240002D01*
X90808D01*
Y239864D01*
X91357D01*
Y239727D01*
X115525D01*
Y239864D01*
X115799D01*
Y240002D01*
X115937D01*
Y240276D01*
X116074D01*
Y246730D01*
X115937D01*
Y247005D01*
X115799D01*
Y247142D01*
X115662D01*
Y247279D01*
X107286D01*
Y247417D01*
X107011D01*
Y247691D01*
X106874D01*
Y256892D01*
X107011D01*
Y257166D01*
X107286D01*
Y257304D01*
X115525D01*
Y257441D01*
X115799D01*
Y257578D01*
X115937D01*
Y257853D01*
X116074D01*
Y264307D01*
X115937D01*
Y264581D01*
X115799D01*
Y264719D01*
X115662D01*
Y264856D01*
D02*
G37*
G36*
X115387Y236843D02*
X115250D01*
Y236706D01*
X115113D01*
Y236843D01*
X86963D01*
Y236706D01*
X86551D01*
Y236569D01*
X86413D01*
Y236431D01*
X86276D01*
Y236157D01*
X86139D01*
Y217207D01*
X86276D01*
Y216520D01*
X86413D01*
Y216108D01*
X86551D01*
Y215834D01*
X86688D01*
Y215696D01*
X86825D01*
Y215559D01*
X86963D01*
Y215422D01*
X87100D01*
Y215284D01*
X87237D01*
Y215147D01*
X87375D01*
Y215010D01*
X87512D01*
Y214872D01*
X87649D01*
Y214735D01*
X87787D01*
Y214598D01*
X87924D01*
Y214461D01*
X88061D01*
Y214323D01*
X88198D01*
Y214186D01*
X88336D01*
Y214049D01*
X88473D01*
Y213911D01*
X88610D01*
Y213774D01*
X88748D01*
Y213637D01*
X88885D01*
Y213499D01*
X89022D01*
Y213362D01*
X89160D01*
Y213225D01*
X89297D01*
Y213087D01*
X89434D01*
Y212950D01*
X89572D01*
Y212813D01*
X89709D01*
Y212675D01*
X89846D01*
Y212538D01*
X89984D01*
Y212401D01*
X90121D01*
Y212263D01*
X90258D01*
Y212126D01*
X90396D01*
Y211989D01*
X90670D01*
Y211852D01*
X91082D01*
Y211714D01*
X101930D01*
Y211852D01*
X102205D01*
Y211989D01*
X102480D01*
Y212126D01*
X102617D01*
Y212263D01*
X102754D01*
Y212401D01*
X102892D01*
Y212538D01*
X103029D01*
Y212675D01*
X103166D01*
Y212813D01*
X103441D01*
Y212950D01*
X103578D01*
Y213087D01*
X103715D01*
Y213225D01*
X103853D01*
Y213362D01*
X103990D01*
Y213499D01*
X104127D01*
Y213637D01*
X104265D01*
Y213774D01*
X104402D01*
Y213911D01*
X104539D01*
Y214049D01*
X104677D01*
Y214186D01*
X104814D01*
Y214323D01*
X104951D01*
Y214461D01*
X105089D01*
Y214598D01*
X105226D01*
Y214735D01*
X105363D01*
Y214872D01*
X105500D01*
Y215010D01*
X105638D01*
Y215147D01*
X105775D01*
Y215284D01*
X105913D01*
Y215422D01*
X106050D01*
Y215559D01*
X106187D01*
Y215696D01*
X106324D01*
Y215834D01*
X106462D01*
Y215971D01*
X106736D01*
Y215834D01*
X106874D01*
Y215696D01*
X107148D01*
Y215559D01*
X107423D01*
Y215422D01*
X107560D01*
Y215284D01*
X107835D01*
Y215147D01*
X108110D01*
Y215010D01*
X108384D01*
Y214872D01*
X108521D01*
Y214735D01*
X108796D01*
Y214598D01*
X109071D01*
Y214461D01*
X109208D01*
Y214323D01*
X109483D01*
Y214186D01*
X109757D01*
Y214049D01*
X109895D01*
Y213911D01*
X110169D01*
Y213774D01*
X110444D01*
Y213637D01*
X110581D01*
Y213499D01*
X110856D01*
Y213362D01*
X111131D01*
Y213225D01*
X111268D01*
Y213087D01*
X111543D01*
Y212950D01*
X111817D01*
Y212813D01*
X111954D01*
Y212675D01*
X112229D01*
Y212538D01*
X112504D01*
Y212401D01*
X112641D01*
Y212263D01*
X112916D01*
Y212126D01*
X113190D01*
Y211989D01*
X113328D01*
Y211852D01*
X113602D01*
Y211714D01*
X113877D01*
Y211577D01*
X114014D01*
Y211439D01*
X114289D01*
Y211302D01*
X114564D01*
Y211165D01*
X114701D01*
Y211028D01*
X114975D01*
Y210890D01*
X115250D01*
Y210753D01*
X115387D01*
Y210616D01*
X115937D01*
Y210753D01*
X116074D01*
Y218443D01*
X115937D01*
Y218717D01*
X115799D01*
Y218855D01*
X115662D01*
Y218992D01*
X115525D01*
Y219129D01*
X115387D01*
Y219267D01*
X115113D01*
Y219404D01*
X114838D01*
Y219541D01*
X114701D01*
Y219679D01*
X114426D01*
Y219816D01*
X114151D01*
Y219953D01*
X113877D01*
Y220091D01*
X113740D01*
Y220228D01*
X113465D01*
Y220365D01*
X113190D01*
Y220502D01*
X113053D01*
Y220640D01*
X112778D01*
Y220777D01*
X112504D01*
Y220914D01*
X112366D01*
Y221052D01*
X112092D01*
Y221189D01*
X111817D01*
Y221326D01*
X111680D01*
Y221464D01*
X111405D01*
Y221601D01*
X111131D01*
Y221738D01*
X110856D01*
Y221876D01*
X110719D01*
Y222013D01*
X110444D01*
Y222150D01*
X110169D01*
Y222288D01*
X110032D01*
Y222425D01*
X109757D01*
Y222562D01*
X109483D01*
Y222700D01*
X109345D01*
Y222837D01*
X109071D01*
Y222974D01*
X108796D01*
Y223111D01*
X108521D01*
Y223249D01*
X108384D01*
Y223386D01*
X108110D01*
Y223524D01*
X107835D01*
Y223661D01*
X107698D01*
Y223798D01*
X107423D01*
Y223935D01*
X107148D01*
Y229153D01*
X107835D01*
Y229291D01*
X107972D01*
Y229153D01*
X115387D01*
Y229291D01*
X115799D01*
Y229428D01*
X115937D01*
Y229565D01*
X116074D01*
Y236294D01*
X115937D01*
Y236569D01*
X115799D01*
Y236706D01*
X115387D01*
Y236843D01*
D02*
G37*
G36*
X78312Y246181D02*
X59225D01*
Y246043D01*
X58538D01*
Y245906D01*
X58126D01*
Y245769D01*
X57989D01*
Y245632D01*
X57851D01*
Y245494D01*
X57714D01*
Y245357D01*
X57577D01*
Y245220D01*
X57439D01*
Y245082D01*
X57302D01*
Y244945D01*
X57165D01*
Y244808D01*
X57027D01*
Y244670D01*
X56890D01*
Y244533D01*
X56753D01*
Y244396D01*
X56616D01*
Y244258D01*
X56478D01*
Y244121D01*
X56341D01*
Y243984D01*
X56203D01*
Y243846D01*
X56066D01*
Y243709D01*
X55929D01*
Y243572D01*
X55792D01*
Y243435D01*
X55654D01*
Y243297D01*
X55517D01*
Y243160D01*
X55380D01*
Y243022D01*
X55242D01*
Y242885D01*
X55105D01*
Y242748D01*
X54968D01*
Y242611D01*
X54830D01*
Y242473D01*
X54693D01*
Y242336D01*
X54556D01*
Y242199D01*
X54418D01*
Y242061D01*
X54281D01*
Y241924D01*
X54144D01*
Y241649D01*
X54007D01*
Y241237D01*
X53869D01*
Y240551D01*
X53732D01*
Y224485D01*
X53869D01*
Y224347D01*
X53732D01*
Y223935D01*
X53869D01*
Y223661D01*
X54007D01*
Y223524D01*
X54144D01*
Y223386D01*
X54418D01*
Y223249D01*
X60323D01*
Y223386D01*
X60460D01*
Y223524D01*
X60598D01*
Y223661D01*
X60735D01*
Y238491D01*
X60872D01*
Y238628D01*
X65679D01*
Y238491D01*
X65816D01*
Y225858D01*
X65953D01*
Y225583D01*
X66228D01*
Y225446D01*
X71308D01*
Y225583D01*
X71583D01*
Y225858D01*
X71720D01*
Y238491D01*
X71858D01*
Y238628D01*
X76526D01*
Y238491D01*
X76664D01*
Y223798D01*
X76801D01*
Y223524D01*
X76939D01*
Y223386D01*
X77213D01*
Y223249D01*
X83118D01*
Y223386D01*
X83392D01*
Y223524D01*
X83530D01*
Y223661D01*
X83667D01*
Y241100D01*
X83530D01*
Y241649D01*
X83392D01*
Y241924D01*
X83255D01*
Y242061D01*
X83118D01*
Y242199D01*
X82980D01*
Y242336D01*
X82843D01*
Y242473D01*
X82706D01*
Y242611D01*
X82569D01*
Y242748D01*
X82431D01*
Y242885D01*
X82294D01*
Y243022D01*
X82157D01*
Y243160D01*
X82019D01*
Y243297D01*
X81882D01*
Y243435D01*
X81745D01*
Y243572D01*
X81607D01*
Y243709D01*
X81470D01*
Y243846D01*
X81333D01*
Y243984D01*
X81195D01*
Y244121D01*
X81058D01*
Y244258D01*
X80921D01*
Y244396D01*
X80783D01*
Y244533D01*
X80646D01*
Y244670D01*
X80509D01*
Y244808D01*
X80371D01*
Y244945D01*
X80234D01*
Y245082D01*
X80097D01*
Y245220D01*
X79960D01*
Y245357D01*
X79822D01*
Y245494D01*
X79685D01*
Y245632D01*
X79548D01*
Y245769D01*
X79273D01*
Y245906D01*
X78998D01*
Y246043D01*
X78312D01*
Y246181D01*
D02*
G37*
G36*
X87787Y305365D02*
X86276D01*
Y303717D01*
X87100D01*
Y303580D01*
X89297D01*
Y303442D01*
X90670D01*
Y303305D01*
X91769D01*
Y303168D01*
X92730D01*
Y303030D01*
X93554D01*
Y302893D01*
X94241D01*
Y302756D01*
X94927D01*
Y302618D01*
X95614D01*
Y302481D01*
X96300D01*
Y302344D01*
X96849D01*
Y302206D01*
X97399D01*
Y302069D01*
X97948D01*
Y301932D01*
X98497D01*
Y301794D01*
X98909D01*
Y301657D01*
X99459D01*
Y301520D01*
X99871D01*
Y301383D01*
X100282D01*
Y301245D01*
X100694D01*
Y301108D01*
X101106D01*
Y300970D01*
X101518D01*
Y300833D01*
X101930D01*
Y300696D01*
X102342D01*
Y300559D01*
X102617D01*
Y300421D01*
X103029D01*
Y300284D01*
X103441D01*
Y300147D01*
X103715D01*
Y300009D01*
X104127D01*
Y299872D01*
X104402D01*
Y299735D01*
X104677D01*
Y299597D01*
X105089D01*
Y299460D01*
X105363D01*
Y299323D01*
X105638D01*
Y299185D01*
X106050D01*
Y299048D01*
X106324D01*
Y298911D01*
X106599D01*
Y298773D01*
X106874D01*
Y298636D01*
X107148D01*
Y298499D01*
X107423D01*
Y298361D01*
X107698D01*
Y298224D01*
X107972D01*
Y298087D01*
X108247D01*
Y297950D01*
X108521D01*
Y297812D01*
X108796D01*
Y297675D01*
X109071D01*
Y297538D01*
X109345D01*
Y297400D01*
X109483D01*
Y297263D01*
X109757D01*
Y297126D01*
X110032D01*
Y296988D01*
X110307D01*
Y296851D01*
X110444D01*
Y296714D01*
X110719D01*
Y296576D01*
X110993D01*
Y296439D01*
X111268D01*
Y296302D01*
X111405D01*
Y296164D01*
X111680D01*
Y296027D01*
X111817D01*
Y295890D01*
X112092D01*
Y295753D01*
X112366D01*
Y295615D01*
X112504D01*
Y295478D01*
X112778D01*
Y295340D01*
X112916D01*
Y295203D01*
X113190D01*
Y295066D01*
X113328D01*
Y294928D01*
X113602D01*
Y294791D01*
X113740D01*
Y294654D01*
X114014D01*
Y294517D01*
X114151D01*
Y294379D01*
X114426D01*
Y294242D01*
X114564D01*
Y294105D01*
X114701D01*
Y293967D01*
X114975D01*
Y293830D01*
X115113D01*
Y293693D01*
X115250D01*
Y293555D01*
X115525D01*
Y293418D01*
X115662D01*
Y293281D01*
X115799D01*
Y293143D01*
X116074D01*
Y293006D01*
X116211D01*
Y292869D01*
X116349D01*
Y292731D01*
X116623D01*
Y292594D01*
X116761D01*
Y292457D01*
X116898D01*
Y292320D01*
X117035D01*
Y292182D01*
X117310D01*
Y292045D01*
X117447D01*
Y291908D01*
X117584D01*
Y291770D01*
X117722D01*
Y291633D01*
X117859D01*
Y291496D01*
X118134D01*
Y291358D01*
X118271D01*
Y291221D01*
X118408D01*
Y291084D01*
X118546D01*
Y290946D01*
X118683D01*
Y290809D01*
X118820D01*
Y290672D01*
X118958D01*
Y290534D01*
X119232D01*
Y290397D01*
X119370D01*
Y290260D01*
X119507D01*
Y290122D01*
X119644D01*
Y289985D01*
X119782D01*
Y289848D01*
X119919D01*
Y289711D01*
X120056D01*
Y289573D01*
X120194D01*
Y289436D01*
X120331D01*
Y289298D01*
X120468D01*
Y289161D01*
X120605D01*
Y289024D01*
X120743D01*
Y288887D01*
X120880D01*
Y288749D01*
X121017D01*
Y288612D01*
X121155D01*
Y288475D01*
X121292D01*
Y288337D01*
X121429D01*
Y288200D01*
X121567D01*
Y288063D01*
X121704D01*
Y287925D01*
X121841D01*
Y287788D01*
X121979D01*
Y287651D01*
X122116D01*
Y287513D01*
X122253D01*
Y287376D01*
X122391D01*
Y287239D01*
X122528D01*
Y287101D01*
X122665D01*
Y286964D01*
X122802D01*
Y286827D01*
X122940D01*
Y286552D01*
X123077D01*
Y286415D01*
X123215D01*
Y286278D01*
X123352D01*
Y286140D01*
X123489D01*
Y286003D01*
X123626D01*
Y285866D01*
X123764D01*
Y285728D01*
X123901D01*
Y285454D01*
X124038D01*
Y285316D01*
X124176D01*
Y285179D01*
X124313D01*
Y285042D01*
X124450D01*
Y284904D01*
X124588D01*
Y284630D01*
X124725D01*
Y284492D01*
X124862D01*
Y284355D01*
X125000D01*
Y284218D01*
X125137D01*
Y283943D01*
X125274D01*
Y283806D01*
X125412D01*
Y283668D01*
X125549D01*
Y283394D01*
X125686D01*
Y283257D01*
X125823D01*
Y283119D01*
X125961D01*
Y282845D01*
X126098D01*
Y282707D01*
X126236D01*
Y282570D01*
X126373D01*
Y282295D01*
X126510D01*
Y282158D01*
X126647D01*
Y282021D01*
X126785D01*
Y281746D01*
X126922D01*
Y281609D01*
X127059D01*
Y281334D01*
X127197D01*
Y281197D01*
X127334D01*
Y280922D01*
X127471D01*
Y280785D01*
X127609D01*
Y280510D01*
X127746D01*
Y280373D01*
X127883D01*
Y280098D01*
X128021D01*
Y279961D01*
X128158D01*
Y279686D01*
X128295D01*
Y279412D01*
X128433D01*
Y279274D01*
X128570D01*
Y279000D01*
X128707D01*
Y278862D01*
X128844D01*
Y278588D01*
X128982D01*
Y278313D01*
X129119D01*
Y278176D01*
X129256D01*
Y277901D01*
X129394D01*
Y277626D01*
X129531D01*
Y277352D01*
X129668D01*
Y277077D01*
X129806D01*
Y276940D01*
X129943D01*
Y276665D01*
X130080D01*
Y276391D01*
X130218D01*
Y276116D01*
X130355D01*
Y275841D01*
X130492D01*
Y275567D01*
X130630D01*
Y275292D01*
X130767D01*
Y275018D01*
X130904D01*
Y274743D01*
X131042D01*
Y274468D01*
X131179D01*
Y274194D01*
X131316D01*
Y273919D01*
X131454D01*
Y273644D01*
X131591D01*
Y273232D01*
X131728D01*
Y272958D01*
X131866D01*
Y272683D01*
X132003D01*
Y272409D01*
X132140D01*
Y271996D01*
X132277D01*
Y271722D01*
X132415D01*
Y271310D01*
X132552D01*
Y271035D01*
X132689D01*
Y270623D01*
X132827D01*
Y270349D01*
X132964D01*
Y269937D01*
X133101D01*
Y269525D01*
X133239D01*
Y269113D01*
X133376D01*
Y268701D01*
X133513D01*
Y268289D01*
X133651D01*
Y267877D01*
X133788D01*
Y267465D01*
X133925D01*
Y267053D01*
X134063D01*
Y266504D01*
X134200D01*
Y266092D01*
X134337D01*
Y265543D01*
X134474D01*
Y264993D01*
X134612D01*
Y264444D01*
X134749D01*
Y263895D01*
X134887D01*
Y263346D01*
X135024D01*
Y262659D01*
X135161D01*
Y261972D01*
X135298D01*
Y261148D01*
X135436D01*
Y260324D01*
X135573D01*
Y259363D01*
X135710D01*
Y258265D01*
X135848D01*
Y257029D01*
X135985D01*
Y254969D01*
X136122D01*
Y249614D01*
X135985D01*
Y249339D01*
X136122D01*
Y249202D01*
X135985D01*
Y247691D01*
X135848D01*
Y246043D01*
X135710D01*
Y245220D01*
X135573D01*
Y244258D01*
X135436D01*
Y243435D01*
X135298D01*
Y242611D01*
X135161D01*
Y241924D01*
X135024D01*
Y241375D01*
X134887D01*
Y240688D01*
X134749D01*
Y240139D01*
X134612D01*
Y239590D01*
X134474D01*
Y239040D01*
X134337D01*
Y238491D01*
X134200D01*
Y238079D01*
X134063D01*
Y237530D01*
X133925D01*
Y237118D01*
X133788D01*
Y236706D01*
X133651D01*
Y236294D01*
X133513D01*
Y235882D01*
X133376D01*
Y235470D01*
X133239D01*
Y235058D01*
X133101D01*
Y234646D01*
X132964D01*
Y234371D01*
X132827D01*
Y233960D01*
X132689D01*
Y233548D01*
X132552D01*
Y233273D01*
X132415D01*
Y232861D01*
X132277D01*
Y232586D01*
X132140D01*
Y232312D01*
X132003D01*
Y231900D01*
X131866D01*
Y231625D01*
X131728D01*
Y231213D01*
X131591D01*
Y230939D01*
X131454D01*
Y230664D01*
X131316D01*
Y230389D01*
X131179D01*
Y230115D01*
X131042D01*
Y229840D01*
X130904D01*
Y229565D01*
X130767D01*
Y229291D01*
X130630D01*
Y229016D01*
X130492D01*
Y228741D01*
X130355D01*
Y228467D01*
X130218D01*
Y228192D01*
X130080D01*
Y227918D01*
X129943D01*
Y227643D01*
X129806D01*
Y227506D01*
X129668D01*
Y227231D01*
X129531D01*
Y226956D01*
X129394D01*
Y226682D01*
X129256D01*
Y226544D01*
X129119D01*
Y226270D01*
X128982D01*
Y225995D01*
X128844D01*
Y225858D01*
X128707D01*
Y225583D01*
X128570D01*
Y225309D01*
X128433D01*
Y225171D01*
X128295D01*
Y224897D01*
X128158D01*
Y224622D01*
X128021D01*
Y224485D01*
X127883D01*
Y224210D01*
X127746D01*
Y224073D01*
X127609D01*
Y223798D01*
X127471D01*
Y223661D01*
X127334D01*
Y223386D01*
X127197D01*
Y223249D01*
X127059D01*
Y222974D01*
X126922D01*
Y222837D01*
X126785D01*
Y222700D01*
X126647D01*
Y222425D01*
X126510D01*
Y222288D01*
X126373D01*
Y222013D01*
X126236D01*
Y221876D01*
X126098D01*
Y221738D01*
X125961D01*
Y221464D01*
X125823D01*
Y221326D01*
X125686D01*
Y221189D01*
X125549D01*
Y220914D01*
X125412D01*
Y220777D01*
X125274D01*
Y220640D01*
X125137D01*
Y220502D01*
X125000D01*
Y220228D01*
X124862D01*
Y220091D01*
X124725D01*
Y219953D01*
X124588D01*
Y219816D01*
X124450D01*
Y219541D01*
X124313D01*
Y219404D01*
X124176D01*
Y219267D01*
X124038D01*
Y219129D01*
X123901D01*
Y218992D01*
X123764D01*
Y218717D01*
X123626D01*
Y218580D01*
X123489D01*
Y218443D01*
X123352D01*
Y218305D01*
X123215D01*
Y218168D01*
X123077D01*
Y218031D01*
X122940D01*
Y217893D01*
X122802D01*
Y217619D01*
X122665D01*
Y217481D01*
X122528D01*
Y217344D01*
X122391D01*
Y217207D01*
X122253D01*
Y217069D01*
X122116D01*
Y216932D01*
X121979D01*
Y216795D01*
X121841D01*
Y216658D01*
X121704D01*
Y216520D01*
X121567D01*
Y216383D01*
X121429D01*
Y216246D01*
X121292D01*
Y216108D01*
X121155D01*
Y215971D01*
X121017D01*
Y215834D01*
X120880D01*
Y215696D01*
X120743D01*
Y215559D01*
X120605D01*
Y215422D01*
X120468D01*
Y215284D01*
X120331D01*
Y215147D01*
X120194D01*
Y215010D01*
X120056D01*
Y214872D01*
X119919D01*
Y214735D01*
X119782D01*
Y214598D01*
X119644D01*
Y214461D01*
X119507D01*
Y214323D01*
X119370D01*
Y214186D01*
X119095D01*
Y214049D01*
X118958D01*
Y213911D01*
X118820D01*
Y211714D01*
X118958D01*
Y211852D01*
X119232D01*
Y211989D01*
X119370D01*
Y212126D01*
X119507D01*
Y212263D01*
X119644D01*
Y212401D01*
X119782D01*
Y212538D01*
X119919D01*
Y212675D01*
X120056D01*
Y212813D01*
X120331D01*
Y212950D01*
X120468D01*
Y213087D01*
X120605D01*
Y213225D01*
X120743D01*
Y213362D01*
X120880D01*
Y213499D01*
X121017D01*
Y213637D01*
X121155D01*
Y213774D01*
X121292D01*
Y213911D01*
X121429D01*
Y214049D01*
X121567D01*
Y214186D01*
X121704D01*
Y214323D01*
X121841D01*
Y214461D01*
X121979D01*
Y214598D01*
X122116D01*
Y214735D01*
X122253D01*
Y214872D01*
X122391D01*
Y215010D01*
X122528D01*
Y215147D01*
X122665D01*
Y215284D01*
X122802D01*
Y215422D01*
X122940D01*
Y215559D01*
X123077D01*
Y215696D01*
X123215D01*
Y215834D01*
X123352D01*
Y215971D01*
X123489D01*
Y216108D01*
X123626D01*
Y216246D01*
X123764D01*
Y216383D01*
X123901D01*
Y216520D01*
X124038D01*
Y216658D01*
X124176D01*
Y216932D01*
X124313D01*
Y217069D01*
X124450D01*
Y217207D01*
X124588D01*
Y217344D01*
X124725D01*
Y217481D01*
X124862D01*
Y217619D01*
X125000D01*
Y217756D01*
X125137D01*
Y218031D01*
X125274D01*
Y218168D01*
X125412D01*
Y218305D01*
X125549D01*
Y218443D01*
X125686D01*
Y218580D01*
X125823D01*
Y218855D01*
X125961D01*
Y218992D01*
X126098D01*
Y219129D01*
X126236D01*
Y219267D01*
X126373D01*
Y219541D01*
X126510D01*
Y219679D01*
X126647D01*
Y219816D01*
X126785D01*
Y219953D01*
X126922D01*
Y220228D01*
X127059D01*
Y220365D01*
X127197D01*
Y220502D01*
X127334D01*
Y220777D01*
X127471D01*
Y220914D01*
X127609D01*
Y221052D01*
X127746D01*
Y221326D01*
X127883D01*
Y221464D01*
X128021D01*
Y221738D01*
X128158D01*
Y221876D01*
X128295D01*
Y222150D01*
X128433D01*
Y222288D01*
X128570D01*
Y222425D01*
X128707D01*
Y222700D01*
X128844D01*
Y222837D01*
X128982D01*
Y223111D01*
X129119D01*
Y223249D01*
X129256D01*
Y223524D01*
X129394D01*
Y223798D01*
X129531D01*
Y223935D01*
X129668D01*
Y224210D01*
X129806D01*
Y224347D01*
X129943D01*
Y224622D01*
X130080D01*
Y224897D01*
X130218D01*
Y225034D01*
X130355D01*
Y225309D01*
X130492D01*
Y225583D01*
X130630D01*
Y225721D01*
X130767D01*
Y225995D01*
X130904D01*
Y226270D01*
X131042D01*
Y226544D01*
X131179D01*
Y226682D01*
X131316D01*
Y226956D01*
X131454D01*
Y227231D01*
X131591D01*
Y227506D01*
X131728D01*
Y227780D01*
X131866D01*
Y228055D01*
X132003D01*
Y228330D01*
X132140D01*
Y228604D01*
X132277D01*
Y228879D01*
X132415D01*
Y229153D01*
X132552D01*
Y229428D01*
X132689D01*
Y229703D01*
X132827D01*
Y229977D01*
X132964D01*
Y230252D01*
X133101D01*
Y230527D01*
X133239D01*
Y230939D01*
X133376D01*
Y231213D01*
X133513D01*
Y231488D01*
X133651D01*
Y231900D01*
X133788D01*
Y232174D01*
X133925D01*
Y232586D01*
X134063D01*
Y232861D01*
X134200D01*
Y233273D01*
X134337D01*
Y233548D01*
X134474D01*
Y233960D01*
X134612D01*
Y234371D01*
X134749D01*
Y234783D01*
X134887D01*
Y235195D01*
X135024D01*
Y235607D01*
X135161D01*
Y236019D01*
X135298D01*
Y236431D01*
X135436D01*
Y236843D01*
X135573D01*
Y237255D01*
X135710D01*
Y237805D01*
X135848D01*
Y238216D01*
X135985D01*
Y238766D01*
X136122D01*
Y239315D01*
X136260D01*
Y239864D01*
X136397D01*
Y240551D01*
X136534D01*
Y241100D01*
X136672D01*
Y241649D01*
X136809D01*
Y242473D01*
X136946D01*
Y243160D01*
X137084D01*
Y243984D01*
X137221D01*
Y244945D01*
X137358D01*
Y246043D01*
X137495D01*
Y247279D01*
X137633D01*
Y249065D01*
X137770D01*
Y255656D01*
X137633D01*
Y257304D01*
X137495D01*
Y258677D01*
X137358D01*
Y259638D01*
X137221D01*
Y260599D01*
X137084D01*
Y261423D01*
X136946D01*
Y262247D01*
X136809D01*
Y262934D01*
X136672D01*
Y263483D01*
X136534D01*
Y264169D01*
X136397D01*
Y264719D01*
X136260D01*
Y265268D01*
X136122D01*
Y265817D01*
X135985D01*
Y266367D01*
X135848D01*
Y266779D01*
X135710D01*
Y267328D01*
X135573D01*
Y267740D01*
X135436D01*
Y268152D01*
X135298D01*
Y268701D01*
X135161D01*
Y269113D01*
X135024D01*
Y269525D01*
X134887D01*
Y269799D01*
X134749D01*
Y270211D01*
X134612D01*
Y270623D01*
X134474D01*
Y271035D01*
X134337D01*
Y271310D01*
X134200D01*
Y271722D01*
X134063D01*
Y271996D01*
X133925D01*
Y272409D01*
X133788D01*
Y272683D01*
X133651D01*
Y273095D01*
X133513D01*
Y273370D01*
X133376D01*
Y273644D01*
X133239D01*
Y274056D01*
X133101D01*
Y274331D01*
X132964D01*
Y274606D01*
X132827D01*
Y274880D01*
X132689D01*
Y275155D01*
X132552D01*
Y275429D01*
X132415D01*
Y275704D01*
X132277D01*
Y275979D01*
X132140D01*
Y276253D01*
X132003D01*
Y276528D01*
X131866D01*
Y276803D01*
X131728D01*
Y277077D01*
X131591D01*
Y277352D01*
X131454D01*
Y277626D01*
X131316D01*
Y277901D01*
X131179D01*
Y278176D01*
X131042D01*
Y278313D01*
X130904D01*
Y278588D01*
X130767D01*
Y278862D01*
X130630D01*
Y279137D01*
X130492D01*
Y279274D01*
X130355D01*
Y279549D01*
X130218D01*
Y279824D01*
X130080D01*
Y279961D01*
X129943D01*
Y280236D01*
X129806D01*
Y280373D01*
X129668D01*
Y280648D01*
X129531D01*
Y280922D01*
X129394D01*
Y281059D01*
X129256D01*
Y281334D01*
X129119D01*
Y281471D01*
X128982D01*
Y281746D01*
X128844D01*
Y281883D01*
X128707D01*
Y282158D01*
X128570D01*
Y282295D01*
X128433D01*
Y282570D01*
X128295D01*
Y282707D01*
X128158D01*
Y282845D01*
X128021D01*
Y283119D01*
X127883D01*
Y283257D01*
X127746D01*
Y283531D01*
X127609D01*
Y283668D01*
X127471D01*
Y283806D01*
X127334D01*
Y284081D01*
X127197D01*
Y284218D01*
X127059D01*
Y284355D01*
X126922D01*
Y284630D01*
X126785D01*
Y284767D01*
X126647D01*
Y284904D01*
X126510D01*
Y285179D01*
X126373D01*
Y285316D01*
X126236D01*
Y285454D01*
X126098D01*
Y285591D01*
X125961D01*
Y285866D01*
X125823D01*
Y286003D01*
X125686D01*
Y286140D01*
X125549D01*
Y286278D01*
X125412D01*
Y286415D01*
X125274D01*
Y286689D01*
X125137D01*
Y286827D01*
X125000D01*
Y286964D01*
X124862D01*
Y287101D01*
X124725D01*
Y287239D01*
X124588D01*
Y287376D01*
X124450D01*
Y287513D01*
X124313D01*
Y287788D01*
X124176D01*
Y287925D01*
X124038D01*
Y288063D01*
X123901D01*
Y288200D01*
X123764D01*
Y288337D01*
X123626D01*
Y288475D01*
X123489D01*
Y288612D01*
X123352D01*
Y288749D01*
X123215D01*
Y288887D01*
X123077D01*
Y289024D01*
X122940D01*
Y289161D01*
X122802D01*
Y289298D01*
X122665D01*
Y289436D01*
X122528D01*
Y289573D01*
X122391D01*
Y289711D01*
X122253D01*
Y289848D01*
X122116D01*
Y289985D01*
X121979D01*
Y290122D01*
X121841D01*
Y290260D01*
X121704D01*
Y290397D01*
X121567D01*
Y290534D01*
X121429D01*
Y290672D01*
X121292D01*
Y290809D01*
X121155D01*
Y290946D01*
X121017D01*
Y291084D01*
X120880D01*
Y291221D01*
X120743D01*
Y291358D01*
X120605D01*
Y291496D01*
X120468D01*
Y291633D01*
X120331D01*
Y291770D01*
X120194D01*
Y291908D01*
X119919D01*
Y292045D01*
X119782D01*
Y292182D01*
X119644D01*
Y292320D01*
X119507D01*
Y292457D01*
X119370D01*
Y292594D01*
X119232D01*
Y292731D01*
X119095D01*
Y292869D01*
X118820D01*
Y293006D01*
X118683D01*
Y293143D01*
X118546D01*
Y293281D01*
X118408D01*
Y293418D01*
X118134D01*
Y293555D01*
X117996D01*
Y293693D01*
X117859D01*
Y293830D01*
X117722D01*
Y293967D01*
X117447D01*
Y294105D01*
X117310D01*
Y294242D01*
X117172D01*
Y294379D01*
X117035D01*
Y294517D01*
X116761D01*
Y294654D01*
X116623D01*
Y294791D01*
X116486D01*
Y294928D01*
X116211D01*
Y295066D01*
X116074D01*
Y295203D01*
X115937D01*
Y295340D01*
X115662D01*
Y295478D01*
X115525D01*
Y295615D01*
X115250D01*
Y295753D01*
X115113D01*
Y295890D01*
X114975D01*
Y296027D01*
X114701D01*
Y296164D01*
X114564D01*
Y296302D01*
X114289D01*
Y296439D01*
X114151D01*
Y296576D01*
X113877D01*
Y296714D01*
X113740D01*
Y296851D01*
X113465D01*
Y296988D01*
X113328D01*
Y297126D01*
X113053D01*
Y297263D01*
X112778D01*
Y297400D01*
X112641D01*
Y297538D01*
X112366D01*
Y297675D01*
X112229D01*
Y297812D01*
X111954D01*
Y297950D01*
X111680D01*
Y298087D01*
X111405D01*
Y298224D01*
X111268D01*
Y298361D01*
X110993D01*
Y298499D01*
X110719D01*
Y298636D01*
X110444D01*
Y298773D01*
X110169D01*
Y298911D01*
X110032D01*
Y299048D01*
X109757D01*
Y299185D01*
X109483D01*
Y299323D01*
X109208D01*
Y299460D01*
X108933D01*
Y299597D01*
X108659D01*
Y299735D01*
X108384D01*
Y299872D01*
X108110D01*
Y300009D01*
X107835D01*
Y300147D01*
X107560D01*
Y300284D01*
X107286D01*
Y300421D01*
X107011D01*
Y300559D01*
X106736D01*
Y300696D01*
X106462D01*
Y300833D01*
X106050D01*
Y300970D01*
X105775D01*
Y301108D01*
X105500D01*
Y301245D01*
X105089D01*
Y301383D01*
X104814D01*
Y301520D01*
X104402D01*
Y301657D01*
X104127D01*
Y301794D01*
X103715D01*
Y301932D01*
X103441D01*
Y302069D01*
X103029D01*
Y302206D01*
X102617D01*
Y302344D01*
X102205D01*
Y302481D01*
X101793D01*
Y302618D01*
X101381D01*
Y302756D01*
X100969D01*
Y302893D01*
X100557D01*
Y303030D01*
X100145D01*
Y303168D01*
X99733D01*
Y303305D01*
X99184D01*
Y303442D01*
X98772D01*
Y303580D01*
X98223D01*
Y303717D01*
X97673D01*
Y303854D01*
X97124D01*
Y303992D01*
X96575D01*
Y304129D01*
X95888D01*
Y304266D01*
X95202D01*
Y304403D01*
X94515D01*
Y304541D01*
X93828D01*
Y304678D01*
X93005D01*
Y304815D01*
X92043D01*
Y304953D01*
X90945D01*
Y305090D01*
X89572D01*
Y305227D01*
X89434D01*
Y305090D01*
X89297D01*
Y305227D01*
X87787D01*
Y305365D01*
D02*
G37*
G36*
X51535Y293693D02*
X51397D01*
Y293555D01*
X51260D01*
Y293418D01*
X51123D01*
Y293281D01*
X50848D01*
Y293143D01*
X50711D01*
Y293006D01*
X50574D01*
Y292869D01*
X50436D01*
Y292731D01*
X50299D01*
Y292594D01*
X50024D01*
Y292457D01*
X49887D01*
Y292320D01*
X49750D01*
Y292182D01*
X49612D01*
Y292045D01*
X49475D01*
Y291908D01*
X49338D01*
Y291770D01*
X49200D01*
Y291633D01*
X49063D01*
Y291496D01*
X48788D01*
Y291358D01*
X48651D01*
Y291221D01*
X48514D01*
Y291084D01*
X48376D01*
Y290946D01*
X48239D01*
Y290809D01*
X48102D01*
Y290672D01*
X47965D01*
Y290534D01*
X47827D01*
Y290397D01*
X47690D01*
Y290260D01*
X47552D01*
Y290122D01*
X47415D01*
Y289985D01*
X47278D01*
Y289848D01*
X47141D01*
Y289711D01*
X47003D01*
Y289573D01*
X46866D01*
Y289436D01*
X46729D01*
Y289298D01*
X46591D01*
Y289161D01*
X46454D01*
Y289024D01*
X46317D01*
Y288887D01*
X46179D01*
Y288749D01*
X46042D01*
Y288612D01*
X45905D01*
Y288475D01*
X45767D01*
Y288337D01*
X45630D01*
Y288200D01*
X45493D01*
Y287925D01*
X45356D01*
Y287788D01*
X45218D01*
Y287651D01*
X45081D01*
Y287513D01*
X44943D01*
Y287376D01*
X44806D01*
Y287239D01*
X44669D01*
Y287101D01*
X44532D01*
Y286964D01*
X44394D01*
Y286689D01*
X44257D01*
Y286552D01*
X44120D01*
Y286415D01*
X43982D01*
Y286278D01*
X43845D01*
Y286140D01*
X43708D01*
Y285866D01*
X43570D01*
Y285728D01*
X43433D01*
Y285591D01*
X43296D01*
Y285454D01*
X43158D01*
Y285179D01*
X43021D01*
Y285042D01*
X42884D01*
Y284904D01*
X42746D01*
Y284767D01*
X42609D01*
Y284492D01*
X42472D01*
Y284355D01*
X42334D01*
Y284218D01*
X42197D01*
Y283943D01*
X42060D01*
Y283806D01*
X41922D01*
Y283668D01*
X41785D01*
Y283394D01*
X41648D01*
Y283257D01*
X41511D01*
Y282982D01*
X41373D01*
Y282845D01*
X41236D01*
Y282707D01*
X41099D01*
Y282433D01*
X40961D01*
Y282295D01*
X40824D01*
Y282021D01*
X40687D01*
Y281883D01*
X40549D01*
Y281609D01*
X40412D01*
Y281471D01*
X40275D01*
Y281197D01*
X40137D01*
Y281059D01*
X40000D01*
Y280785D01*
X39863D01*
Y280648D01*
X39725D01*
Y280373D01*
X39588D01*
Y280098D01*
X39451D01*
Y279961D01*
X39313D01*
Y279686D01*
X39176D01*
Y279412D01*
X39039D01*
Y279274D01*
X38902D01*
Y279000D01*
X38764D01*
Y278725D01*
X38627D01*
Y278588D01*
X38490D01*
Y278313D01*
X38352D01*
Y278039D01*
X38215D01*
Y277764D01*
X38078D01*
Y277489D01*
X37940D01*
Y277352D01*
X37803D01*
Y277077D01*
X37666D01*
Y276803D01*
X37528D01*
Y276528D01*
X37391D01*
Y276253D01*
X37254D01*
Y275979D01*
X37116D01*
Y275704D01*
X36979D01*
Y275429D01*
X36842D01*
Y275155D01*
X36704D01*
Y274880D01*
X36567D01*
Y274468D01*
X36430D01*
Y274194D01*
X36293D01*
Y273919D01*
X36155D01*
Y273644D01*
X36018D01*
Y273232D01*
X35880D01*
Y272958D01*
X35743D01*
Y272683D01*
X35606D01*
Y272271D01*
X35469D01*
Y271996D01*
X35331D01*
Y271585D01*
X35194D01*
Y271310D01*
X35057D01*
Y270898D01*
X34919D01*
Y270486D01*
X34782D01*
Y270074D01*
X34645D01*
Y269799D01*
X34507D01*
Y269387D01*
X34370D01*
Y268976D01*
X34233D01*
Y268564D01*
X34095D01*
Y268014D01*
X33958D01*
Y267602D01*
X33821D01*
Y267190D01*
X33684D01*
Y266641D01*
X33546D01*
Y266229D01*
X33409D01*
Y265680D01*
X33272D01*
Y265131D01*
X33134D01*
Y264581D01*
X32997D01*
Y264032D01*
X32860D01*
Y263346D01*
X32722D01*
Y262659D01*
X32585D01*
Y261972D01*
X32448D01*
Y261148D01*
X32310D01*
Y260187D01*
X32173D01*
Y259363D01*
X32036D01*
Y258265D01*
X31898D01*
Y256892D01*
X31761D01*
Y254832D01*
X31624D01*
Y249751D01*
X31761D01*
Y247691D01*
X31898D01*
Y246455D01*
X32036D01*
Y245357D01*
X32173D01*
Y244258D01*
X32310D01*
Y243435D01*
X32448D01*
Y242611D01*
X32585D01*
Y241924D01*
X32722D01*
Y241237D01*
X32860D01*
Y240551D01*
X32997D01*
Y240002D01*
X33134D01*
Y239452D01*
X33272D01*
Y238903D01*
X33409D01*
Y238354D01*
X33546D01*
Y237942D01*
X33684D01*
Y237393D01*
X33821D01*
Y236981D01*
X33958D01*
Y236569D01*
X34095D01*
Y236019D01*
X34233D01*
Y235607D01*
X34370D01*
Y235195D01*
X34507D01*
Y234921D01*
X34645D01*
Y234509D01*
X34782D01*
Y234097D01*
X34919D01*
Y233685D01*
X35057D01*
Y233410D01*
X35194D01*
Y232998D01*
X35331D01*
Y232586D01*
X35469D01*
Y232312D01*
X35606D01*
Y231900D01*
X35743D01*
Y231625D01*
X35880D01*
Y231350D01*
X36018D01*
Y230939D01*
X36155D01*
Y230664D01*
X36293D01*
Y230389D01*
X36430D01*
Y230115D01*
X36567D01*
Y229840D01*
X36704D01*
Y229428D01*
X36842D01*
Y229153D01*
X36979D01*
Y229016D01*
X37116D01*
Y228741D01*
X37254D01*
Y228330D01*
X37391D01*
Y228055D01*
X37528D01*
Y227918D01*
X37666D01*
Y227506D01*
X37803D01*
Y227368D01*
X37940D01*
Y227094D01*
X38078D01*
Y226819D01*
X38215D01*
Y226544D01*
X38352D01*
Y226270D01*
X38490D01*
Y226133D01*
X38627D01*
Y225858D01*
X38764D01*
Y225583D01*
X38902D01*
Y225309D01*
X39039D01*
Y225171D01*
X39176D01*
Y224897D01*
X39313D01*
Y224622D01*
X39451D01*
Y224485D01*
X39588D01*
Y224210D01*
X39725D01*
Y224073D01*
X39863D01*
Y223798D01*
X40000D01*
Y223524D01*
X40137D01*
Y223386D01*
X40275D01*
Y223111D01*
X40412D01*
Y222974D01*
X40549D01*
Y222700D01*
X40687D01*
Y222562D01*
X40824D01*
Y222288D01*
X40961D01*
Y222150D01*
X41099D01*
Y221876D01*
X41236D01*
Y221738D01*
X41373D01*
Y221601D01*
X41511D01*
Y221326D01*
X41648D01*
Y221189D01*
X41785D01*
Y221052D01*
X41922D01*
Y220777D01*
X42060D01*
Y220640D01*
X42197D01*
Y220365D01*
X42334D01*
Y220228D01*
X42472D01*
Y220091D01*
X42609D01*
Y219953D01*
X42746D01*
Y219679D01*
X42884D01*
Y219541D01*
X43021D01*
Y219404D01*
X43158D01*
Y219129D01*
X43296D01*
Y218992D01*
X43433D01*
Y218855D01*
X43570D01*
Y218717D01*
X43708D01*
Y218580D01*
X43845D01*
Y218305D01*
X43982D01*
Y218168D01*
X44120D01*
Y218031D01*
X44257D01*
Y217893D01*
X44394D01*
Y217756D01*
X44532D01*
Y217481D01*
X44669D01*
Y217344D01*
X44806D01*
Y217207D01*
X44943D01*
Y217069D01*
X45081D01*
Y216932D01*
X45218D01*
Y216795D01*
X45356D01*
Y216658D01*
X45493D01*
Y216520D01*
X45630D01*
Y216383D01*
X45767D01*
Y216108D01*
X45905D01*
Y215971D01*
X46042D01*
Y215834D01*
X46179D01*
Y215696D01*
X46317D01*
Y215559D01*
X46454D01*
Y215422D01*
X46591D01*
Y215284D01*
X46729D01*
Y215147D01*
X46866D01*
Y215010D01*
X47003D01*
Y214872D01*
X47141D01*
Y214735D01*
X47278D01*
Y214598D01*
X47415D01*
Y214461D01*
X47552D01*
Y214323D01*
X47690D01*
Y214186D01*
X47827D01*
Y214049D01*
X47965D01*
Y213911D01*
X48102D01*
Y213774D01*
X48239D01*
Y213637D01*
X48376D01*
Y213499D01*
X48514D01*
Y213362D01*
X48651D01*
Y213225D01*
X48926D01*
Y213087D01*
X49063D01*
Y212950D01*
X49200D01*
Y212813D01*
X49338D01*
Y212675D01*
X49475D01*
Y212538D01*
X49612D01*
Y212401D01*
X49750D01*
Y212263D01*
X49887D01*
Y212126D01*
X50162D01*
Y211989D01*
X50299D01*
Y211852D01*
X50436D01*
Y211714D01*
X50574D01*
Y211577D01*
X50711D01*
Y211439D01*
X50985D01*
Y211302D01*
X51123D01*
Y211165D01*
X51260D01*
Y211028D01*
X51397D01*
Y210890D01*
X51535D01*
Y210753D01*
X51809D01*
Y210616D01*
X51947D01*
Y210478D01*
X52084D01*
Y210341D01*
X52359D01*
Y210204D01*
X52496D01*
Y210066D01*
X52633D01*
Y209929D01*
X52771D01*
Y209792D01*
X53045D01*
Y209654D01*
X53183D01*
Y209517D01*
X53320D01*
Y209380D01*
X53594D01*
Y209242D01*
X53732D01*
Y209105D01*
X54007D01*
Y208968D01*
X54144D01*
Y208831D01*
X54281D01*
Y208693D01*
X54556D01*
Y208556D01*
X54693D01*
Y208419D01*
X54968D01*
Y208281D01*
X55105D01*
Y208144D01*
X55380D01*
Y208007D01*
X55517D01*
Y207869D01*
X55792D01*
Y207732D01*
X55929D01*
Y207595D01*
X56203D01*
Y207457D01*
X56341D01*
Y207320D01*
X56616D01*
Y207183D01*
X56890D01*
Y207045D01*
X57027D01*
Y206908D01*
X57302D01*
Y206771D01*
X57577D01*
Y206633D01*
X57714D01*
Y206496D01*
X57989D01*
Y206359D01*
X58263D01*
Y206221D01*
X58401D01*
Y206084D01*
X58675D01*
Y205947D01*
X58950D01*
Y205809D01*
X59225D01*
Y205672D01*
X59499D01*
Y205535D01*
X59637D01*
Y205397D01*
X59911D01*
Y205260D01*
X60186D01*
Y205123D01*
X60460D01*
Y204986D01*
X60735D01*
Y204848D01*
X61010D01*
Y204711D01*
X61284D01*
Y204574D01*
X61559D01*
Y204436D01*
X61834D01*
Y204299D01*
X62108D01*
Y204162D01*
X62520D01*
Y204024D01*
X62795D01*
Y203887D01*
X63069D01*
Y203750D01*
X63344D01*
Y203612D01*
X63756D01*
Y203475D01*
X64031D01*
Y203338D01*
X64305D01*
Y203200D01*
X64717D01*
Y203063D01*
X64992D01*
Y202926D01*
X65404D01*
Y202789D01*
X65679D01*
Y202651D01*
X66090D01*
Y202514D01*
X66502D01*
Y202377D01*
X66777D01*
Y202239D01*
X67189D01*
Y202102D01*
X67601D01*
Y201965D01*
X68013D01*
Y201827D01*
X68425D01*
Y201690D01*
X68837D01*
Y201553D01*
X69386D01*
Y201415D01*
X69798D01*
Y201278D01*
X70347D01*
Y201141D01*
X70759D01*
Y201003D01*
X71308D01*
Y200866D01*
X71858D01*
Y200729D01*
X72407D01*
Y200591D01*
X72956D01*
Y200454D01*
X73643D01*
Y200317D01*
X74329D01*
Y200180D01*
X75016D01*
Y200042D01*
X75703D01*
Y199905D01*
X76526D01*
Y199767D01*
X77488D01*
Y199630D01*
X78586D01*
Y199493D01*
X79960D01*
Y199356D01*
X81882D01*
Y199218D01*
X82294D01*
Y199356D01*
X82431D01*
Y199218D01*
X84079D01*
Y200866D01*
X82569D01*
Y201003D01*
X80234D01*
Y201141D01*
X78998D01*
Y201278D01*
X77762D01*
Y201415D01*
X76801D01*
Y201553D01*
X75977D01*
Y201690D01*
X75291D01*
Y201827D01*
X74467D01*
Y201965D01*
X73917D01*
Y202102D01*
X73231D01*
Y202239D01*
X72682D01*
Y202377D01*
X72132D01*
Y202514D01*
X71583D01*
Y202651D01*
X71034D01*
Y202789D01*
X70622D01*
Y202926D01*
X70073D01*
Y203063D01*
X69661D01*
Y203200D01*
X69249D01*
Y203338D01*
X68699D01*
Y203475D01*
X68288D01*
Y203612D01*
X67875D01*
Y203750D01*
X67601D01*
Y203887D01*
X67189D01*
Y204024D01*
X66777D01*
Y204162D01*
X66365D01*
Y204299D01*
X66090D01*
Y204436D01*
X65679D01*
Y204574D01*
X65404D01*
Y204711D01*
X64992D01*
Y204848D01*
X64717D01*
Y204986D01*
X64443D01*
Y205123D01*
X64031D01*
Y205260D01*
X63756D01*
Y205397D01*
X63481D01*
Y205535D01*
X63207D01*
Y205672D01*
X62932D01*
Y205809D01*
X62657D01*
Y205947D01*
X62245D01*
Y206084D01*
X61971D01*
Y206221D01*
X61696D01*
Y206359D01*
X61422D01*
Y206496D01*
X61147D01*
Y206633D01*
X61010D01*
Y206771D01*
X60735D01*
Y206908D01*
X60460D01*
Y207045D01*
X60186D01*
Y207183D01*
X59911D01*
Y207320D01*
X59637D01*
Y207457D01*
X59499D01*
Y207595D01*
X59225D01*
Y207732D01*
X58950D01*
Y207869D01*
X58675D01*
Y208007D01*
X58538D01*
Y208144D01*
X58263D01*
Y208281D01*
X57989D01*
Y208419D01*
X57851D01*
Y208556D01*
X57577D01*
Y208693D01*
X57302D01*
Y208831D01*
X57165D01*
Y208968D01*
X56890D01*
Y209105D01*
X56753D01*
Y209242D01*
X56478D01*
Y209380D01*
X56341D01*
Y209517D01*
X56066D01*
Y209654D01*
X55929D01*
Y209792D01*
X55654D01*
Y209929D01*
X55517D01*
Y210066D01*
X55242D01*
Y210204D01*
X55105D01*
Y210341D01*
X54968D01*
Y210478D01*
X54693D01*
Y210616D01*
X54556D01*
Y210753D01*
X54281D01*
Y210890D01*
X54144D01*
Y211028D01*
X54007D01*
Y211165D01*
X53732D01*
Y211302D01*
X53594D01*
Y211439D01*
X53457D01*
Y211577D01*
X53183D01*
Y211714D01*
X53045D01*
Y211852D01*
X52908D01*
Y211989D01*
X52771D01*
Y212126D01*
X52496D01*
Y212263D01*
X52359D01*
Y212401D01*
X52221D01*
Y212538D01*
X52084D01*
Y212675D01*
X51809D01*
Y212813D01*
X51672D01*
Y212950D01*
X51535D01*
Y213087D01*
X51397D01*
Y213225D01*
X51260D01*
Y213362D01*
X51123D01*
Y213499D01*
X50848D01*
Y213637D01*
X50711D01*
Y213774D01*
X50574D01*
Y213911D01*
X50436D01*
Y214049D01*
X50299D01*
Y214186D01*
X50162D01*
Y214323D01*
X50024D01*
Y214461D01*
X49887D01*
Y214598D01*
X49750D01*
Y214735D01*
X49475D01*
Y214872D01*
X49338D01*
Y215010D01*
X49200D01*
Y215147D01*
X49063D01*
Y215284D01*
X48926D01*
Y215422D01*
X48788D01*
Y215559D01*
X48651D01*
Y215696D01*
X48514D01*
Y215834D01*
X48376D01*
Y215971D01*
X48239D01*
Y216108D01*
X48102D01*
Y216246D01*
X47965D01*
Y216383D01*
X47827D01*
Y216520D01*
X47690D01*
Y216658D01*
X47552D01*
Y216795D01*
X47415D01*
Y216932D01*
X47278D01*
Y217069D01*
X47141D01*
Y217344D01*
X47003D01*
Y217481D01*
X46866D01*
Y217619D01*
X46729D01*
Y217756D01*
X46591D01*
Y217893D01*
X46454D01*
Y218031D01*
X46317D01*
Y218168D01*
X46179D01*
Y218305D01*
X46042D01*
Y218443D01*
X45905D01*
Y218717D01*
X45767D01*
Y218855D01*
X45630D01*
Y218992D01*
X45493D01*
Y219129D01*
X45356D01*
Y219267D01*
X45218D01*
Y219404D01*
X45081D01*
Y219679D01*
X44943D01*
Y219816D01*
X44806D01*
Y219953D01*
X44669D01*
Y220091D01*
X44532D01*
Y220365D01*
X44394D01*
Y220502D01*
X44257D01*
Y220640D01*
X44120D01*
Y220777D01*
X43982D01*
Y221052D01*
X43845D01*
Y221189D01*
X43708D01*
Y221326D01*
X43570D01*
Y221601D01*
X43433D01*
Y221738D01*
X43296D01*
Y221876D01*
X43158D01*
Y222150D01*
X43021D01*
Y222288D01*
X42884D01*
Y222562D01*
X42746D01*
Y222700D01*
X42609D01*
Y222837D01*
X42472D01*
Y223111D01*
X42334D01*
Y223249D01*
X42197D01*
Y223524D01*
X42060D01*
Y223661D01*
X41922D01*
Y223935D01*
X41785D01*
Y224073D01*
X41648D01*
Y224347D01*
X41511D01*
Y224485D01*
X41373D01*
Y224759D01*
X41236D01*
Y224897D01*
X41099D01*
Y225171D01*
X40961D01*
Y225446D01*
X40824D01*
Y225583D01*
X40687D01*
Y225858D01*
X40549D01*
Y226133D01*
X40412D01*
Y226270D01*
X40275D01*
Y226544D01*
X40137D01*
Y226819D01*
X40000D01*
Y227094D01*
X39863D01*
Y227231D01*
X39725D01*
Y227506D01*
X39588D01*
Y227780D01*
X39451D01*
Y228055D01*
X39313D01*
Y228330D01*
X39176D01*
Y228604D01*
X39039D01*
Y228879D01*
X38902D01*
Y229153D01*
X38764D01*
Y229428D01*
X38627D01*
Y229565D01*
X38490D01*
Y229840D01*
X38352D01*
Y230252D01*
X38215D01*
Y230527D01*
X38078D01*
Y230801D01*
X37940D01*
Y231076D01*
X37803D01*
Y231350D01*
X37666D01*
Y231763D01*
X37528D01*
Y232037D01*
X37391D01*
Y232312D01*
X37254D01*
Y232724D01*
X37116D01*
Y232998D01*
X36979D01*
Y233410D01*
X36842D01*
Y233685D01*
X36704D01*
Y234097D01*
X36567D01*
Y234371D01*
X36430D01*
Y234783D01*
X36293D01*
Y235195D01*
X36155D01*
Y235607D01*
X36018D01*
Y236019D01*
X35880D01*
Y236431D01*
X35743D01*
Y236843D01*
X35606D01*
Y237255D01*
X35469D01*
Y237667D01*
X35331D01*
Y238216D01*
X35194D01*
Y238628D01*
X35057D01*
Y239178D01*
X34919D01*
Y239727D01*
X34782D01*
Y240276D01*
X34645D01*
Y240826D01*
X34507D01*
Y241512D01*
X34370D01*
Y242199D01*
X34233D01*
Y242885D01*
X34095D01*
Y243709D01*
X33958D01*
Y244533D01*
X33821D01*
Y245357D01*
X33684D01*
Y246593D01*
X33546D01*
Y248103D01*
X33409D01*
Y250300D01*
X33272D01*
Y250438D01*
X33409D01*
Y250575D01*
X33272D01*
Y254008D01*
X33409D01*
Y256480D01*
X33546D01*
Y257990D01*
X33684D01*
Y259089D01*
X33821D01*
Y260050D01*
X33958D01*
Y260874D01*
X34095D01*
Y261835D01*
X34233D01*
Y262384D01*
X34370D01*
Y263071D01*
X34507D01*
Y263757D01*
X34645D01*
Y264307D01*
X34782D01*
Y264856D01*
X34919D01*
Y265405D01*
X35057D01*
Y265955D01*
X35194D01*
Y266367D01*
X35331D01*
Y266916D01*
X35469D01*
Y267328D01*
X35606D01*
Y267740D01*
X35743D01*
Y268152D01*
X35880D01*
Y268701D01*
X36018D01*
Y268976D01*
X36155D01*
Y269387D01*
X36293D01*
Y269799D01*
X36430D01*
Y270211D01*
X36567D01*
Y270486D01*
X36704D01*
Y270898D01*
X36842D01*
Y271310D01*
X36979D01*
Y271585D01*
X37116D01*
Y271996D01*
X37254D01*
Y272271D01*
X37391D01*
Y272546D01*
X37528D01*
Y272958D01*
X37666D01*
Y273232D01*
X37803D01*
Y273507D01*
X37940D01*
Y273782D01*
X38078D01*
Y274056D01*
X38215D01*
Y274331D01*
X38352D01*
Y274743D01*
X38490D01*
Y275018D01*
X38627D01*
Y275292D01*
X38764D01*
Y275567D01*
X38902D01*
Y275841D01*
X39039D01*
Y275979D01*
X39176D01*
Y276253D01*
X39313D01*
Y276528D01*
X39451D01*
Y276803D01*
X39588D01*
Y277077D01*
X39725D01*
Y277352D01*
X39863D01*
Y277626D01*
X40000D01*
Y277764D01*
X40137D01*
Y278039D01*
X40275D01*
Y278313D01*
X40412D01*
Y278450D01*
X40549D01*
Y278725D01*
X40687D01*
Y279000D01*
X40824D01*
Y279137D01*
X40961D01*
Y279412D01*
X41099D01*
Y279686D01*
X41236D01*
Y279824D01*
X41373D01*
Y280098D01*
X41511D01*
Y280236D01*
X41648D01*
Y280510D01*
X41785D01*
Y280648D01*
X41922D01*
Y280922D01*
X42060D01*
Y281059D01*
X42197D01*
Y281334D01*
X42334D01*
Y281471D01*
X42472D01*
Y281746D01*
X42609D01*
Y281883D01*
X42746D01*
Y282158D01*
X42884D01*
Y282295D01*
X43021D01*
Y282433D01*
X43158D01*
Y282707D01*
X43296D01*
Y282845D01*
X43433D01*
Y282982D01*
X43570D01*
Y283257D01*
X43708D01*
Y283394D01*
X43845D01*
Y283531D01*
X43982D01*
Y283806D01*
X44120D01*
Y283943D01*
X44257D01*
Y284081D01*
X44394D01*
Y284218D01*
X44532D01*
Y284492D01*
X44669D01*
Y284630D01*
X44806D01*
Y284767D01*
X44943D01*
Y284904D01*
X45081D01*
Y285179D01*
X45218D01*
Y285316D01*
X45356D01*
Y285454D01*
X45493D01*
Y285591D01*
X45630D01*
Y285728D01*
X45767D01*
Y286003D01*
X45905D01*
Y286140D01*
X46042D01*
Y286278D01*
X46179D01*
Y286415D01*
X46317D01*
Y286552D01*
X46454D01*
Y286689D01*
X46591D01*
Y286827D01*
X46729D01*
Y286964D01*
X46866D01*
Y287101D01*
X47003D01*
Y287376D01*
X47141D01*
Y287513D01*
X47278D01*
Y287651D01*
X47415D01*
Y287788D01*
X47552D01*
Y287925D01*
X47690D01*
Y288063D01*
X47827D01*
Y288200D01*
X47965D01*
Y288337D01*
X48102D01*
Y288475D01*
X48239D01*
Y288612D01*
X48376D01*
Y288749D01*
X48514D01*
Y288887D01*
X48651D01*
Y289024D01*
X48788D01*
Y289161D01*
X48926D01*
Y289298D01*
X49063D01*
Y289436D01*
X49200D01*
Y289573D01*
X49338D01*
Y289711D01*
X49475D01*
Y289848D01*
X49612D01*
Y289985D01*
X49750D01*
Y290122D01*
X50024D01*
Y290260D01*
X50162D01*
Y290397D01*
X50299D01*
Y290534D01*
X50436D01*
Y290672D01*
X50574D01*
Y290809D01*
X50711D01*
Y290946D01*
X50848D01*
Y291084D01*
X50985D01*
Y291221D01*
X51260D01*
Y291358D01*
X51397D01*
Y291496D01*
X51535D01*
Y293693D01*
D02*
G37*
G36*
X115662Y207595D02*
X86688D01*
Y207457D01*
X86551D01*
Y207320D01*
X86413D01*
Y207183D01*
X86276D01*
Y206908D01*
X86139D01*
Y187958D01*
X86276D01*
Y187272D01*
X86413D01*
Y186860D01*
X86551D01*
Y186722D01*
X86688D01*
Y186585D01*
X86825D01*
Y186448D01*
X86963D01*
Y186310D01*
X87100D01*
Y186173D01*
X87237D01*
Y186036D01*
X87375D01*
Y185898D01*
X87512D01*
Y185761D01*
X87649D01*
Y185624D01*
X87787D01*
Y185487D01*
X87924D01*
Y185349D01*
X88061D01*
Y185212D01*
X88198D01*
Y185075D01*
X88336D01*
Y184937D01*
X88473D01*
Y184800D01*
X88610D01*
Y184663D01*
X88748D01*
Y184525D01*
X88885D01*
Y184388D01*
X89022D01*
Y184251D01*
X89160D01*
Y184113D01*
X89297D01*
Y183976D01*
X89434D01*
Y183839D01*
X89572D01*
Y183701D01*
X89709D01*
Y183564D01*
X89846D01*
Y183427D01*
X89984D01*
Y183289D01*
X90121D01*
Y183152D01*
X90258D01*
Y183015D01*
X90396D01*
Y182878D01*
X90533D01*
Y182740D01*
X90808D01*
Y182603D01*
X91357D01*
Y182465D01*
X110856D01*
Y182603D01*
X111405D01*
Y182740D01*
X111817D01*
Y182878D01*
X111954D01*
Y183015D01*
X112092D01*
Y183152D01*
X112229D01*
Y183289D01*
X112366D01*
Y183427D01*
X112504D01*
Y183564D01*
X112641D01*
Y183701D01*
X112778D01*
Y183839D01*
X112916D01*
Y183976D01*
X113053D01*
Y184113D01*
X113190D01*
Y184251D01*
X113328D01*
Y184388D01*
X113465D01*
Y184525D01*
X113602D01*
Y184663D01*
X113740D01*
Y184800D01*
X113877D01*
Y184937D01*
X114014D01*
Y185075D01*
X114151D01*
Y185212D01*
X114289D01*
Y185349D01*
X114426D01*
Y185487D01*
X114564D01*
Y185624D01*
X114701D01*
Y185761D01*
X114838D01*
Y185898D01*
X114975D01*
Y186036D01*
X115113D01*
Y186173D01*
X115250D01*
Y186310D01*
X115387D01*
Y186448D01*
X115525D01*
Y186585D01*
X115662D01*
Y186722D01*
X115799D01*
Y186997D01*
X115937D01*
Y187546D01*
X116074D01*
Y207183D01*
X115937D01*
Y207320D01*
X115799D01*
Y207457D01*
X115662D01*
Y207595D01*
D02*
G37*
%LPD*%
G36*
X100420Y219267D02*
X93142D01*
Y229565D01*
X100420D01*
Y219267D01*
D02*
G37*
G36*
X108796Y190018D02*
X93554D01*
Y190293D01*
X93417D01*
Y190430D01*
X93554D01*
Y190705D01*
X93417D01*
Y190842D01*
X93554D01*
Y199767D01*
X93417D01*
Y199905D01*
X93554D01*
Y200042D01*
X108796D01*
Y190018D01*
D02*
G37*
%LPC*%
G36*
X192783Y299195D02*
X189935Y298137D01*
X189583Y298011D01*
X189244Y297912D01*
X188934Y297813D01*
X188652Y297743D01*
X188413Y297686D01*
X188314Y297658D01*
X188215Y297644D01*
X188159Y297616D01*
X188103D01*
X188074Y297602D01*
X188060D01*
X188384Y297503D01*
X188723Y297390D01*
X189061Y297278D01*
X189385Y297165D01*
X189526Y297108D01*
X189667Y297066D01*
X189794Y297024D01*
X189893Y296982D01*
X189977Y296953D01*
X190048Y296925D01*
X190090Y296911D01*
X190104D01*
X192783Y295896D01*
Y299195D01*
D02*
G37*
G36*
X207012Y280121D02*
X206942D01*
X206928D01*
X206815Y280107D01*
X206702Y280093D01*
X206618Y280065D01*
X206533Y280037D01*
X206462Y280009D01*
X206406Y279995D01*
X206378Y279966D01*
X206364D01*
X206195Y279825D01*
X206082Y279656D01*
X206040Y279600D01*
X206011Y279543D01*
X205983Y279501D01*
Y279487D01*
X205927Y279346D01*
X205885Y279191D01*
X205842Y279022D01*
X205814Y278853D01*
X205786Y278698D01*
X205758Y278557D01*
X205744Y278472D01*
Y278444D01*
X205701Y278204D01*
X205673Y277979D01*
X205631Y277781D01*
X205588Y277584D01*
X205546Y277401D01*
X205504Y277246D01*
X205476Y277091D01*
X205433Y276964D01*
X205405Y276851D01*
X205377Y276752D01*
X205349Y276668D01*
X205321Y276597D01*
X205307Y276541D01*
X205292Y276499D01*
X205278Y276484D01*
Y276470D01*
X205730Y276484D01*
X206011Y276499D01*
X206251Y276513D01*
X206448Y276541D01*
X206618Y276583D01*
X206744Y276625D01*
X206843Y276654D01*
X206900Y276668D01*
X206914Y276682D01*
X207097Y276795D01*
X207266Y276907D01*
X207407Y277048D01*
X207520Y277175D01*
X207619Y277288D01*
X207689Y277387D01*
X207731Y277443D01*
X207745Y277471D01*
X207844Y277683D01*
X207915Y277894D01*
X207971Y278092D01*
X207999Y278289D01*
X208027Y278444D01*
X208041Y278585D01*
Y278698D01*
X208027Y278951D01*
X207999Y279163D01*
X207943Y279346D01*
X207886Y279501D01*
X207830Y279614D01*
X207773Y279699D01*
X207745Y279755D01*
X207731Y279769D01*
X207604Y279882D01*
X207463Y279966D01*
X207337Y280037D01*
X207210Y280079D01*
X207097Y280107D01*
X207012Y280121D01*
D02*
G37*
G36*
X194982Y275216D02*
X194911D01*
X194897D01*
X194785Y275202D01*
X194672Y275187D01*
X194587Y275159D01*
X194503Y275131D01*
X194432Y275103D01*
X194376Y275089D01*
X194348Y275061D01*
X194333D01*
X194164Y274920D01*
X194051Y274750D01*
X194009Y274694D01*
X193981Y274638D01*
X193953Y274595D01*
Y274581D01*
X193897Y274440D01*
X193854Y274285D01*
X193812Y274116D01*
X193784Y273947D01*
X193755Y273792D01*
X193727Y273651D01*
X193713Y273566D01*
Y273538D01*
X193671Y273298D01*
X193643Y273073D01*
X193600Y272876D01*
X193558Y272678D01*
X193516Y272495D01*
X193474Y272340D01*
X193445Y272185D01*
X193403Y272058D01*
X193375Y271945D01*
X193347Y271847D01*
X193319Y271762D01*
X193290Y271691D01*
X193276Y271635D01*
X193262Y271593D01*
X193248Y271579D01*
Y271565D01*
X193699Y271579D01*
X193981Y271593D01*
X194221Y271607D01*
X194418Y271635D01*
X194587Y271677D01*
X194714Y271720D01*
X194813Y271748D01*
X194869Y271762D01*
X194883Y271776D01*
X195067Y271889D01*
X195236Y272002D01*
X195377Y272143D01*
X195489Y272269D01*
X195588Y272382D01*
X195659Y272481D01*
X195701Y272537D01*
X195715Y272565D01*
X195814Y272777D01*
X195884Y272988D01*
X195940Y273186D01*
X195969Y273383D01*
X195997Y273538D01*
X196011Y273679D01*
Y273792D01*
X195997Y274046D01*
X195969Y274257D01*
X195912Y274440D01*
X195856Y274595D01*
X195800Y274708D01*
X195743Y274793D01*
X195715Y274849D01*
X195701Y274863D01*
X195574Y274976D01*
X195433Y275061D01*
X195306Y275131D01*
X195179Y275173D01*
X195067Y275202D01*
X194982Y275216D01*
D02*
G37*
G36*
X193403Y260146D02*
X193333D01*
X193290D01*
X193276D01*
X193022D01*
X192783Y260118D01*
X192557Y260090D01*
X192360Y260061D01*
X192177Y260019D01*
X192008Y259977D01*
X191852Y259935D01*
X191711Y259878D01*
X191599Y259822D01*
X191500Y259779D01*
X191415Y259737D01*
X191345Y259695D01*
X191289Y259653D01*
X191246Y259639D01*
X191232Y259610D01*
X191218D01*
X191105Y259512D01*
X190993Y259399D01*
X190837Y259173D01*
X190711Y258948D01*
X190640Y258736D01*
X190584Y258553D01*
X190570Y258398D01*
X190555Y258342D01*
Y258271D01*
X190570Y258116D01*
X190584Y257975D01*
X190668Y257707D01*
X190767Y257468D01*
X190894Y257270D01*
X191021Y257115D01*
X191133Y256988D01*
X191218Y256918D01*
X191232Y256890D01*
X191246D01*
X191387Y256791D01*
X191528Y256706D01*
X191866Y256565D01*
X192219Y256467D01*
X192557Y256396D01*
X192726Y256368D01*
X192882Y256354D01*
X193022Y256340D01*
X193135D01*
X193234Y256326D01*
X193304D01*
X193361D01*
X193375D01*
X193615D01*
X193840Y256354D01*
X194037Y256382D01*
X194235Y256410D01*
X194404Y256453D01*
X194573Y256509D01*
X194714Y256551D01*
X194841Y256608D01*
X194954Y256664D01*
X195067Y256706D01*
X195137Y256763D01*
X195208Y256805D01*
X195264Y256833D01*
X195306Y256861D01*
X195320Y256890D01*
X195334D01*
X195447Y256988D01*
X195546Y257101D01*
X195701Y257327D01*
X195814Y257552D01*
X195884Y257764D01*
X195940Y257947D01*
X195955Y258102D01*
X195969Y258158D01*
Y258229D01*
X195955Y258370D01*
X195940Y258511D01*
X195870Y258764D01*
X195757Y259004D01*
X195630Y259202D01*
X195518Y259357D01*
X195405Y259484D01*
X195334Y259554D01*
X195306Y259568D01*
Y259582D01*
X195165Y259681D01*
X195024Y259765D01*
X194700Y259906D01*
X194362Y260005D01*
X194037Y260075D01*
X193741Y260118D01*
X193615Y260132D01*
X193502D01*
X193403Y260146D01*
D02*
G37*
G36*
X193389Y252562D02*
X193319D01*
X193276D01*
X193262D01*
X193022Y252548D01*
X192783Y252534D01*
X192571Y252505D01*
X192374Y252463D01*
X192191Y252421D01*
X192022Y252379D01*
X191881Y252322D01*
X191740Y252266D01*
X191627Y252209D01*
X191514Y252153D01*
X191430Y252111D01*
X191359Y252068D01*
X191303Y252026D01*
X191260Y251998D01*
X191246Y251970D01*
X191232D01*
X191119Y251857D01*
X191007Y251730D01*
X190837Y251490D01*
X190725Y251237D01*
X190640Y250997D01*
X190584Y250786D01*
X190570Y250630D01*
X190555Y250560D01*
Y250476D01*
X190570Y250306D01*
X190584Y250151D01*
X190654Y249869D01*
X190767Y249616D01*
X190894Y249404D01*
X191021Y249235D01*
X191119Y249108D01*
X191204Y249023D01*
X191218Y248995D01*
X191232D01*
X191359Y248883D01*
X191514Y248798D01*
X191824Y248643D01*
X192162Y248530D01*
X192473Y248460D01*
X192769Y248417D01*
X192896Y248403D01*
X193008D01*
X193093Y248389D01*
X193163D01*
X193206D01*
X193220D01*
X193474D01*
X193713Y248417D01*
X193925Y248445D01*
X194136Y248488D01*
X194319Y248530D01*
X194489Y248587D01*
X194644Y248629D01*
X194785Y248685D01*
X194897Y248741D01*
X195010Y248798D01*
X195095Y248854D01*
X195165Y248897D01*
X195222Y248939D01*
X195264Y248967D01*
X195278Y248981D01*
X195292Y248995D01*
X195405Y249108D01*
X195518Y249235D01*
X195687Y249475D01*
X195800Y249728D01*
X195884Y249954D01*
X195926Y250165D01*
X195955Y250320D01*
X195969Y250391D01*
Y250476D01*
X195955Y250645D01*
X195940Y250800D01*
X195870Y251096D01*
X195757Y251350D01*
X195630Y251561D01*
X195518Y251730D01*
X195405Y251857D01*
X195334Y251942D01*
X195306Y251956D01*
Y251970D01*
X195165Y252068D01*
X195024Y252167D01*
X194700Y252308D01*
X194362Y252421D01*
X194023Y252491D01*
X193727Y252534D01*
X193600Y252548D01*
X193488D01*
X193389Y252562D01*
D02*
G37*
G36*
X191683Y240509D02*
X188201D01*
Y237718D01*
X188215Y237464D01*
X188230Y237253D01*
X188244Y237083D01*
X188272Y236971D01*
X188286Y236886D01*
X188300Y236830D01*
Y236815D01*
X188370Y236632D01*
X188455Y236477D01*
X188540Y236336D01*
X188638Y236209D01*
X188737Y236125D01*
X188807Y236054D01*
X188864Y236012D01*
X188878Y235998D01*
X189047Y235899D01*
X189216Y235815D01*
X189400Y235758D01*
X189555Y235730D01*
X189696Y235702D01*
X189822Y235688D01*
X189893D01*
X189907D01*
X189921D01*
X190217Y235716D01*
X190471Y235772D01*
X190696Y235857D01*
X190880Y235956D01*
X191021Y236054D01*
X191133Y236139D01*
X191190Y236195D01*
X191218Y236223D01*
X191303Y236322D01*
X191373Y236449D01*
X191486Y236717D01*
X191570Y237013D01*
X191627Y237309D01*
X191655Y237577D01*
X191669Y237689D01*
Y237788D01*
X191683Y237887D01*
Y240509D01*
D02*
G37*
G36*
X207012Y233869D02*
X206942D01*
X206928D01*
X206815Y233855D01*
X206702Y233841D01*
X206618Y233813D01*
X206533Y233785D01*
X206462Y233756D01*
X206406Y233742D01*
X206378Y233714D01*
X206364D01*
X206195Y233573D01*
X206082Y233404D01*
X206040Y233348D01*
X206011Y233291D01*
X205983Y233249D01*
Y233235D01*
X205927Y233094D01*
X205885Y232939D01*
X205842Y232770D01*
X205814Y232600D01*
X205786Y232445D01*
X205758Y232304D01*
X205744Y232220D01*
Y232192D01*
X205701Y231952D01*
X205673Y231726D01*
X205631Y231529D01*
X205588Y231332D01*
X205546Y231148D01*
X205504Y230993D01*
X205476Y230838D01*
X205433Y230711D01*
X205405Y230599D01*
X205377Y230500D01*
X205349Y230415D01*
X205321Y230345D01*
X205307Y230289D01*
X205292Y230246D01*
X205278Y230232D01*
Y230218D01*
X205730Y230232D01*
X206011Y230246D01*
X206251Y230260D01*
X206448Y230289D01*
X206618Y230331D01*
X206744Y230373D01*
X206843Y230401D01*
X206900Y230415D01*
X206914Y230429D01*
X207097Y230542D01*
X207266Y230655D01*
X207407Y230796D01*
X207520Y230923D01*
X207619Y231036D01*
X207689Y231134D01*
X207731Y231191D01*
X207745Y231219D01*
X207844Y231430D01*
X207915Y231642D01*
X207971Y231839D01*
X207999Y232037D01*
X208027Y232192D01*
X208041Y232333D01*
Y232445D01*
X208027Y232699D01*
X207999Y232911D01*
X207943Y233094D01*
X207886Y233249D01*
X207830Y233362D01*
X207773Y233446D01*
X207745Y233503D01*
X207731Y233517D01*
X207604Y233630D01*
X207463Y233714D01*
X207337Y233785D01*
X207210Y233827D01*
X207097Y233855D01*
X207012Y233869D01*
D02*
G37*
G36*
X194982Y221379D02*
X194911D01*
X194897D01*
X194785Y221365D01*
X194672Y221351D01*
X194587Y221323D01*
X194503Y221295D01*
X194432Y221266D01*
X194376Y221252D01*
X194348Y221224D01*
X194333D01*
X194164Y221083D01*
X194051Y220914D01*
X194009Y220858D01*
X193981Y220801D01*
X193953Y220759D01*
Y220745D01*
X193897Y220604D01*
X193854Y220449D01*
X193812Y220280D01*
X193784Y220110D01*
X193755Y219956D01*
X193727Y219814D01*
X193713Y219730D01*
Y219702D01*
X193671Y219462D01*
X193643Y219237D01*
X193600Y219039D01*
X193558Y218842D01*
X193516Y218659D01*
X193474Y218503D01*
X193445Y218348D01*
X193403Y218221D01*
X193375Y218109D01*
X193347Y218010D01*
X193319Y217925D01*
X193290Y217855D01*
X193276Y217799D01*
X193262Y217756D01*
X193248Y217742D01*
Y217728D01*
X193699Y217742D01*
X193981Y217756D01*
X194221Y217770D01*
X194418Y217799D01*
X194587Y217841D01*
X194714Y217883D01*
X194813Y217911D01*
X194869Y217925D01*
X194883Y217940D01*
X195067Y218052D01*
X195236Y218165D01*
X195377Y218306D01*
X195489Y218433D01*
X195588Y218546D01*
X195659Y218644D01*
X195701Y218701D01*
X195715Y218729D01*
X195814Y218941D01*
X195884Y219152D01*
X195940Y219349D01*
X195969Y219547D01*
X195997Y219702D01*
X196011Y219843D01*
Y219956D01*
X195997Y220209D01*
X195969Y220421D01*
X195912Y220604D01*
X195856Y220759D01*
X195800Y220872D01*
X195743Y220956D01*
X195715Y221013D01*
X195701Y221027D01*
X195574Y221140D01*
X195433Y221224D01*
X195306Y221295D01*
X195179Y221337D01*
X195067Y221365D01*
X194982Y221379D01*
D02*
G37*
G36*
X204616Y214909D02*
X204292Y214866D01*
X203996Y214782D01*
X203742Y214683D01*
X203544Y214570D01*
X203375Y214472D01*
X203248Y214373D01*
X203178Y214317D01*
X203150Y214289D01*
X202966Y214063D01*
X202826Y213837D01*
X202727Y213598D01*
X202656Y213372D01*
X202614Y213189D01*
X202600Y213034D01*
X202586Y212978D01*
Y212893D01*
X202600Y212724D01*
X202614Y212569D01*
X202699Y212273D01*
X202811Y212019D01*
X202938Y211807D01*
X203065Y211638D01*
X203178Y211511D01*
X203263Y211441D01*
X203277Y211413D01*
X203291D01*
X203474Y211286D01*
X203685Y211173D01*
X203897Y211103D01*
X204122Y211032D01*
X204306Y210990D01*
X204475Y210962D01*
X204531D01*
X204573Y210947D01*
X204602D01*
X204616D01*
Y214909D01*
D02*
G37*
G36*
X192585Y210750D02*
X192261Y210708D01*
X191965Y210623D01*
X191711Y210525D01*
X191514Y210412D01*
X191345Y210313D01*
X191218Y210214D01*
X191147Y210158D01*
X191119Y210130D01*
X190936Y209904D01*
X190795Y209679D01*
X190696Y209439D01*
X190626Y209214D01*
X190584Y209030D01*
X190570Y208875D01*
X190555Y208819D01*
Y208734D01*
X190570Y208565D01*
X190584Y208410D01*
X190668Y208114D01*
X190781Y207860D01*
X190908Y207649D01*
X191035Y207480D01*
X191147Y207353D01*
X191232Y207282D01*
X191246Y207254D01*
X191260D01*
X191444Y207127D01*
X191655Y207014D01*
X191866Y206944D01*
X192092Y206873D01*
X192275Y206831D01*
X192444Y206803D01*
X192501D01*
X192543Y206789D01*
X192571D01*
X192585D01*
Y210750D01*
D02*
G37*
%LPD*%
D16*
X200328Y33332D02*
Y30000D01*
X203661Y33332D01*
X204494D01*
X205327Y32499D01*
Y30833D01*
X204494Y30000D01*
X151000Y30332D02*
Y27000D01*
X154332Y30332D01*
X155165D01*
X155998Y29499D01*
Y27833D01*
X155165Y27000D01*
Y31998D02*
X155998Y32831D01*
Y34497D01*
X155165Y35331D01*
X151833D01*
X151000Y34497D01*
Y32831D01*
X151833Y31998D01*
X155165D01*
X177000Y28000D02*
Y29666D01*
Y28833D01*
X181998D01*
X181165Y28000D01*
Y32165D02*
X181998Y32998D01*
Y34664D01*
X181165Y35498D01*
X177833D01*
X177000Y34664D01*
Y32998D01*
X177833Y32165D01*
X181165D01*
X21998Y29000D02*
Y32332D01*
X21165D01*
X17833Y29000D01*
X17000D01*
Y36497D02*
X21998D01*
X19499Y33998D01*
Y37331D01*
M02*
